G04 ================== begin FILE IDENTIFICATION RECORD ==================*
G04 Layout Name:  D:/<user>/Wistron_project/16342-2/gbr/16342-2.brd*
G04 Film Name:    L5VCC*
G04 File Format:  Gerber RS274X*
G04 File Origin:  Cadence Allegro 16.5-S056*
G04 Origin Date:  Mon Aug 07 11:24:47 2017*
G04 *
G04 Layer:  VIA CLASS/L5VCC*
G04 Layer:  PIN/L5VCC*
G04 Layer:  PACKAGE GEOMETRY/PWRVCC*
G04 Layer:  ETCH/L5VCC*
G04 Layer:  DRAWING FORMAT/LAYER_PCB_STORY*
G04 Layer:  DRAWING FORMAT/LAYER_L5VCC*
G04 *
G04 Offset:    (0.00 0.00)*
G04 Mirror:    No*
G04 Mode:      Negative*
G04 Rotation:  0*
G04 FullContactRelief:  No*
G04 UndefLineWidth:     6.00*
G04 ================== end FILE IDENTIFICATION RECORD ====================*
%FSLAX35Y35*MOIN*%
%IR0*IPPOS*OFA0.00000B0.00000*MIA0B0*SFA1.00000B1.00000*%
%ADD28O,.072X.123*%
%ADD12C,.03*%
%ADD25C,.032*%
%ADD23C,.06*%
%ADD32C,.043*%
%ADD31C,.062*%
%ADD39C,.063*%
%ADD36C,.072*%
%ADD21C,.036*%
%ADD38C,.091*%
%ADD22C,.028*%
%ADD27C,.056*%
%ADD30C,.076*%
%ADD10C,.068*%
%AMMACRO40*
4,1,15,.00398,.00044,
.003999,.000208,
.004004,-.000025,
.003996,-.000258,
.00398,-.00044,
.00483,-.00129,
.004897,-.001007,
.004947,-.000721,
.004981,-.000432,
.004997,-.000141,
.004997,.000149,
.00498,.00044,
.004946,.000729,
.004895,.001015,
.00483,.00129,
.00398,.00044,
45.*
4,1,15,.00044,-.00398,
.000208,-.003999,
-.000025,-.004004,
-.000258,-.003996,
-.00044,-.00398,
-.00129,-.00483,
-.001007,-.004897,
-.000721,-.004947,
-.000432,-.004981,
-.000141,-.004997,
.000149,-.004997,
.00044,-.00498,
.000729,-.004946,
.001015,-.004895,
.00129,-.00483,
.00044,-.00398,
45.*
4,1,15,-.00398,-.00044,
-.003999,-.000208,
-.004004,.000025,
-.003996,.000258,
-.00398,.00044,
-.00483,.00129,
-.004897,.001007,
-.004947,.000721,
-.004981,.000432,
-.004997,.000141,
-.004997,-.000149,
-.00498,-.00044,
-.004946,-.000729,
-.004895,-.001015,
-.00483,-.00129,
-.00398,-.00044,
45.*
4,1,15,-.00044,.00398,
-.000208,.003999,
.000025,.004004,
.000258,.003996,
.00044,.00398,
.00129,.00483,
.001007,.004897,
.000721,.004947,
.000432,.004981,
.000141,.004997,
-.000149,.004997,
-.00044,.00498,
-.000729,.004946,
-.001015,.004895,
-.00129,.00483,
-.00044,.00398,
45.*
%
%ADD40MACRO40*%
%AMMACRO17*
4,1,15,.00398,.00044,
.003999,.000208,
.004004,-.000025,
.003996,-.000258,
.00398,-.00044,
.00483,-.00129,
.004897,-.001007,
.004947,-.000721,
.004981,-.000432,
.004997,-.000141,
.004997,.000149,
.00498,.00044,
.004946,.000729,
.004895,.001015,
.00483,.00129,
.00398,.00044,
90.*
4,1,15,.00044,-.00398,
.000208,-.003999,
-.000025,-.004004,
-.000258,-.003996,
-.00044,-.00398,
-.00129,-.00483,
-.001007,-.004897,
-.000721,-.004947,
-.000432,-.004981,
-.000141,-.004997,
.000149,-.004997,
.00044,-.00498,
.000729,-.004946,
.001015,-.004895,
.00129,-.00483,
.00044,-.00398,
90.*
4,1,15,-.00398,-.00044,
-.003999,-.000208,
-.004004,.000025,
-.003996,.000258,
-.00398,.00044,
-.00483,.00129,
-.004897,.001007,
-.004947,.000721,
-.004981,.000432,
-.004997,.000141,
-.004997,-.000149,
-.00498,-.00044,
-.004946,-.000729,
-.004895,-.001015,
-.00483,-.00129,
-.00398,-.00044,
90.*
4,1,15,-.00044,.00398,
-.000208,.003999,
.000025,.004004,
.000258,.003996,
.00044,.00398,
.00129,.00483,
.001007,.004897,
.000721,.004947,
.000432,.004981,
.000141,.004997,
-.000149,.004997,
-.00044,.00498,
-.000729,.004946,
-.001015,.004895,
-.00129,.00483,
-.00044,.00398,
90.*
%
%ADD17MACRO17*%
%AMMACRO11*
4,1,15,.00398,.00044,
.003999,.000208,
.004004,-.000025,
.003996,-.000258,
.00398,-.00044,
.00483,-.00129,
.004897,-.001007,
.004947,-.000721,
.004981,-.000432,
.004997,-.000141,
.004997,.000149,
.00498,.00044,
.004946,.000729,
.004895,.001015,
.00483,.00129,
.00398,.00044,
0.0*
4,1,15,.00044,-.00398,
.000208,-.003999,
-.000025,-.004004,
-.000258,-.003996,
-.00044,-.00398,
-.00129,-.00483,
-.001007,-.004897,
-.000721,-.004947,
-.000432,-.004981,
-.000141,-.004997,
.000149,-.004997,
.00044,-.00498,
.000729,-.004946,
.001015,-.004895,
.00129,-.00483,
.00044,-.00398,
0.0*
4,1,15,-.00398,-.00044,
-.003999,-.000208,
-.004004,.000025,
-.003996,.000258,
-.00398,.00044,
-.00483,.00129,
-.004897,.001007,
-.004947,.000721,
-.004981,.000432,
-.004997,.000141,
-.004997,-.000149,
-.00498,-.00044,
-.004946,-.000729,
-.004895,-.001015,
-.00483,-.00129,
-.00398,-.00044,
0.0*
4,1,15,-.00044,.00398,
-.000208,.003999,
.000025,.004004,
.000258,.003996,
.00044,.00398,
.00129,.00483,
.001007,.004897,
.000721,.004947,
.000432,.004981,
.000141,.004997,
-.000149,.004997,
-.00044,.00498,
-.000729,.004946,
-.001015,.004895,
-.00129,.00483,
-.00044,.00398,
0.0*
%
%ADD11MACRO11*%
%ADD35O,.154X.217*%
%ADD34C,.122*%
%ADD13C,.114*%
%ADD33C,.125*%
%ADD24C,.208*%
%ADD19O,.296X.162*%
%ADD29O,.072X.096*%
%ADD20C,.158*%
%ADD14C,.178*%
%ADD18C,.198*%
%AMMACRO37*
4,1,15,.00398,.00044,
.003999,.000208,
.004004,-.000025,
.003996,-.000258,
.00398,-.00044,
.00483,-.00129,
.004897,-.001007,
.004947,-.000721,
.004981,-.000432,
.004997,-.000141,
.004997,.000149,
.00498,.00044,
.004946,.000729,
.004895,.001015,
.00483,.00129,
.00398,.00044,
225.*
4,1,15,.00044,-.00398,
.000208,-.003999,
-.000025,-.004004,
-.000258,-.003996,
-.00044,-.00398,
-.00129,-.00483,
-.001007,-.004897,
-.000721,-.004947,
-.000432,-.004981,
-.000141,-.004997,
.000149,-.004997,
.00044,-.00498,
.000729,-.004946,
.001015,-.004895,
.00129,-.00483,
.00044,-.00398,
225.*
4,1,15,-.00398,-.00044,
-.003999,-.000208,
-.004004,.000025,
-.003996,.000258,
-.00398,.00044,
-.00483,.00129,
-.004897,.001007,
-.004947,.000721,
-.004981,.000432,
-.004997,.000141,
-.004997,-.000149,
-.00498,-.00044,
-.004946,-.000729,
-.004895,-.001015,
-.00483,-.00129,
-.00398,-.00044,
225.*
4,1,15,-.00044,.00398,
-.000208,.003999,
.000025,.004004,
.000258,.003996,
.00044,.00398,
.00129,.00483,
.001007,.004897,
.000721,.004947,
.000432,.004981,
.000141,.004997,
-.000149,.004997,
-.00044,.00498,
-.000729,.004946,
-.001015,.004895,
-.00129,.00483,
-.00044,.00398,
225.*
%
%ADD37MACRO37*%
%AMMACRO16*
4,1,15,.00398,.00044,
.003999,.000208,
.004004,-.000025,
.003996,-.000258,
.00398,-.00044,
.00483,-.00129,
.004897,-.001007,
.004947,-.000721,
.004981,-.000432,
.004997,-.000141,
.004997,.000149,
.00498,.00044,
.004946,.000729,
.004895,.001015,
.00483,.00129,
.00398,.00044,
180.*
4,1,15,.00044,-.00398,
.000208,-.003999,
-.000025,-.004004,
-.000258,-.003996,
-.00044,-.00398,
-.00129,-.00483,
-.001007,-.004897,
-.000721,-.004947,
-.000432,-.004981,
-.000141,-.004997,
.000149,-.004997,
.00044,-.00498,
.000729,-.004946,
.001015,-.004895,
.00129,-.00483,
.00044,-.00398,
180.*
4,1,15,-.00398,-.00044,
-.003999,-.000208,
-.004004,.000025,
-.003996,.000258,
-.00398,.00044,
-.00483,.00129,
-.004897,.001007,
-.004947,.000721,
-.004981,.000432,
-.004997,.000141,
-.004997,-.000149,
-.00498,-.00044,
-.004946,-.000729,
-.004895,-.001015,
-.00483,-.00129,
-.00398,-.00044,
180.*
4,1,15,-.00044,.00398,
-.000208,.003999,
.000025,.004004,
.000258,.003996,
.00044,.00398,
.00129,.00483,
.001007,.004897,
.000721,.004947,
.000432,.004981,
.000141,.004997,
-.000149,.004997,
-.00044,.00498,
-.000729,.004946,
-.001015,.004895,
-.00129,.00483,
-.00044,.00398,
180.*
%
%ADD16MACRO16*%
%AMMACRO15*
4,1,15,.00398,.00044,
.003999,.000208,
.004004,-.000025,
.003996,-.000258,
.00398,-.00044,
.00483,-.00129,
.004897,-.001007,
.004947,-.000721,
.004981,-.000432,
.004997,-.000141,
.004997,.000149,
.00498,.00044,
.004946,.000729,
.004895,.001015,
.00483,.00129,
.00398,.00044,
270.*
4,1,15,.00044,-.00398,
.000208,-.003999,
-.000025,-.004004,
-.000258,-.003996,
-.00044,-.00398,
-.00129,-.00483,
-.001007,-.004897,
-.000721,-.004947,
-.000432,-.004981,
-.000141,-.004997,
.000149,-.004997,
.00044,-.00498,
.000729,-.004946,
.001015,-.004895,
.00129,-.00483,
.00044,-.00398,
270.*
4,1,15,-.00398,-.00044,
-.003999,-.000208,
-.004004,.000025,
-.003996,.000258,
-.00398,.00044,
-.00483,.00129,
-.004897,.001007,
-.004947,.000721,
-.004981,.000432,
-.004997,.000141,
-.004997,-.000149,
-.00498,-.00044,
-.004946,-.000729,
-.004895,-.001015,
-.00483,-.00129,
-.00398,-.00044,
270.*
4,1,15,-.00044,.00398,
-.000208,.003999,
.000025,.004004,
.000258,.003996,
.00044,.00398,
.00129,.00483,
.001007,.004897,
.000721,.004947,
.000432,.004981,
.000141,.004997,
-.000149,.004997,
-.00044,.00498,
-.000729,.004946,
-.001015,.004895,
-.00129,.00483,
-.00044,.00398,
270.*
%
%ADD15MACRO15*%
%AMMACRO26*
4,1,19,.02172,.00757,
.022123,.006294,
.022452,.004997,
.022705,.003683,
.02288,.002357,
.022979,.001023,
.022999,-.000315,
.022942,-.001652,
.022807,-.002983,
.022595,-.004304,
.022307,-.005611,
.021943,-.006898,
.02172,-.00757,
.02556,-.01142,
.027155,-.006808,
.027924,-.001989,
.027846,.00289,
.026921,.007681,
.02556,.01142,
.02172,.00757,
0.0*
4,1,19,.00757,-.02172,
.006294,-.022123,
.004997,-.022452,
.003683,-.022705,
.002357,-.02288,
.001023,-.022979,
-.000315,-.022999,
-.001652,-.022942,
-.002983,-.022807,
-.004304,-.022595,
-.005611,-.022307,
-.006898,-.021943,
-.00757,-.02172,
-.01142,-.02556,
-.006808,-.027155,
-.001989,-.027924,
.00289,-.027846,
.007681,-.026921,
.01142,-.02556,
.00757,-.02172,
0.0*
4,1,19,-.02172,-.00757,
-.022123,-.006294,
-.022452,-.004997,
-.022705,-.003683,
-.02288,-.002357,
-.022979,-.001023,
-.022999,.000315,
-.022942,.001652,
-.022807,.002983,
-.022595,.004304,
-.022307,.005611,
-.021943,.006898,
-.02172,.00757,
-.02556,.01142,
-.027155,.006808,
-.027924,.001989,
-.027846,-.00289,
-.026921,-.007681,
-.02556,-.01142,
-.02172,-.00757,
0.0*
4,1,19,-.00757,.02172,
-.006294,.022123,
-.004997,.022452,
-.003683,.022705,
-.002357,.02288,
-.001023,.022979,
.000315,.022999,
.001652,.022942,
.002983,.022807,
.004304,.022595,
.005611,.022307,
.006898,.021943,
.00757,.02172,
.01142,.02556,
.006808,.027155,
.001989,.027924,
-.00289,.027846,
-.007681,.026921,
-.01142,.02556,
-.00757,.02172,
0.0*
%
%ADD26MACRO26*%
%ADD41C,.02*%
%ADD42C,.006*%
%ADD54C,.07204*%
%ADD53C,.05604*%
%ADD55C,.05804*%
%ADD58C,.06804*%
%ADD59C,.08704*%
%ADD43C,.08382*%
%ADD44C,.08982*%
%ADD46O,.15002X.21302*%
%ADD45O,.15004X.21304*%
%ADD50C,.11004*%
%ADD56C,.12104*%
%ADD57C,.11804*%
%ADD51C,.15404*%
%ADD47O,.29202X.15802*%
%ADD48O,.29204X.15804*%
%ADD49C,.37406*%
%ADD52C,.29604*%
G75*
%LPD*%
G75*
G36*
G01X-6000Y-6000D02*
X931197D01*
Y769780D01*
X-6000D01*
Y-6000D01*
G37*
%LPC*%
G75*
G36*
G01X606592Y624139D02*
G03X617818I5613J-17840D01*
G02X617936Y624921I119J382D01*
G01X842520D01*
G03X851457Y633858I0J8937D01*
G01Y758780D01*
X870256D01*
G02X870375Y757998I-1J-400D01*
G03X881593I5609J-17841D01*
G02X881712Y758780I120J382D01*
G01X902421D01*
X920197Y723229D01*
Y5000D01*
X695561D01*
X694250Y6311D01*
Y10589D01*
X698811Y15150D01*
X785011D01*
X800513Y30652D01*
X812308D01*
X812527Y30871D01*
Y30872D01*
X853906Y72250D01*
X904711D01*
X908648Y76187D01*
Y113513D01*
X903911Y118250D01*
X853992D01*
X786992Y51250D01*
X684639D01*
X665639Y32250D01*
X600240D01*
X592419Y24429D01*
X590933D01*
X590897Y24583D01*
G03X586609I-2144J-503D01*
G01X586573Y24429D01*
X496753D01*
X496731Y24434D01*
G03X495753I-489J-2147D01*
G01X495731Y24429D01*
X417900D01*
G02X417641Y25133I0J400D01*
G03X393383I-12129J14237D01*
G02X393124Y24429I-259J-304D01*
G01X354517D01*
X334133Y44813D01*
Y106551D01*
X345986Y118404D01*
X363957D01*
X369047Y123494D01*
Y129578D01*
X352742Y145883D01*
Y168000D01*
X346939Y173803D01*
Y196806D01*
G03X346719Y197336I-750J-1D01*
G01X340932Y203123D01*
G03X340402Y203343I-531J-530D01*
G01X323672D01*
X323623Y203474D01*
G03X318627Y203067I-2441J-900D01*
G01X318615Y203006D01*
X316039Y200429D01*
G03X315819Y199899I530J-531D01*
G01Y169319D01*
X320321Y164817D01*
Y136416D01*
X305286Y121380D01*
G03X305066Y120850I530J-531D01*
G01Y11076D01*
X304915Y11038D01*
G03X304153Y6316I631J-2524D01*
G02X304222Y5696I-214J-338D01*
G01X303774Y5248D01*
G03X303658Y5098I530J-530D01*
G01X303600Y5000D01*
X292520D01*
Y429331D01*
G03X283583Y438268I-8937J0D01*
G01X124134D01*
G03X115197Y429331I0J-8937D01*
G01Y5000D01*
X5000D01*
Y723229D01*
X22776Y758780D01*
X43484D01*
G02X43603Y757998I-1J-400D01*
G03X54821I5609J-17841D01*
G02X54940Y758780I120J382D01*
G01X358445D01*
G02X358564Y757998I-1J-400D01*
G03X369782I5609J-17841D01*
G02X369901Y758780I120J382D01*
G01X385492D01*
X403268Y723229D01*
Y188976D01*
G03X415090Y183976I6969J0D01*
G01X561288D01*
G03X573110Y188975I4853J5000D01*
G01Y294405D01*
G02X573809Y294670I400J0D01*
G03Y319504I13986J12417D01*
G02X573110Y319769I-299J265D01*
G01Y463810D01*
G02X573867Y463990I400J-1D01*
G03Y480892I16684J8451D01*
G02X573110Y481072I-357J181D01*
G01Y589370D01*
X590885Y624921D01*
X606474D01*
G02X606592Y624139I-1J-400D01*
G37*
G36*
G01X692750Y6511D02*
X691239Y5000D01*
X308002D01*
X307946Y5108D01*
G03X307809Y5296I-667J-342D01*
G01X307182Y5923D01*
G02X307210Y6513I283J282D01*
G03X306566Y10908I-1664J2001D01*
G01Y120539D01*
X321821Y135794D01*
Y165439D01*
X317319Y169941D01*
Y199588D01*
X318627Y200896D01*
G02X319212Y200874I282J-283D01*
G03X323636Y201709I1970J1700D01*
G01X323683Y201843D01*
X340091D01*
X345439Y196495D01*
Y173181D01*
X351242Y167378D01*
Y145261D01*
X367547Y128956D01*
Y124116D01*
X363335Y119904D01*
X345364D01*
X332853Y107392D01*
G03X332633Y106862I530J-531D01*
G01Y44191D01*
X353895Y22929D01*
X396597D01*
G03X414427I8915J16441D01*
G01X438099D01*
X438114Y22927D01*
G03X438886I386J2573D01*
G01X438901Y22929D01*
X586876D01*
G03X590630I1877J1151D01*
G01X593041D01*
X600862Y30750D01*
X613550D01*
X613568Y30747D01*
G03X614496I464J2560D01*
G01X614514Y30750D01*
X666261D01*
X685261Y49750D01*
X787614D01*
X854614Y116750D01*
X903289D01*
X907148Y112891D01*
Y76809D01*
X904089Y73750D01*
X853284D01*
X811686Y32152D01*
X799891D01*
X784389Y16650D01*
X698189D01*
X692750Y11211D01*
Y6511D01*
G37*
%LPD*%
G75*
G36*
G01X326672Y372018D02*
Y375519D01*
G02X329692Y375518I1510J-1D01*
G01Y372018D01*
G02X326672I-1510J0D01*
G37*
G36*
G01X302757Y365792D02*
Y369293D01*
G02X305777Y369292I1510J-1D01*
G01Y365792D01*
G02X302757I-1510J0D01*
G37*
G36*
G01X333072Y359474D02*
Y362975D01*
G02X336092Y362974I1510J-1D01*
G01Y359474D01*
G02X333072I-1510J0D01*
G37*
G36*
G01X306057Y353192D02*
Y356693D01*
G02X309077Y356692I1510J-1D01*
G01Y353192D01*
G02X306057I-1510J0D01*
G37*
G36*
G01X326677Y346816D02*
Y350317D01*
G02X329697Y350316I1510J-1D01*
G01Y346816D01*
G02X326677I-1510J0D01*
G37*
G36*
G01X302757Y340592D02*
Y344093D01*
G02X305777Y344092I1510J-1D01*
G01Y340592D01*
G02X302757I-1510J0D01*
G37*
G36*
G01X333072Y334221D02*
Y337722D01*
G02X336092Y337721I1510J-1D01*
G01Y334221D01*
G02X333072I-1510J0D01*
G37*
G36*
G01X306057Y327992D02*
Y331493D01*
G02X309077Y331492I1510J-1D01*
G01Y327992D01*
G02X306057I-1510J0D01*
G37*
G36*
G01X326672Y321624D02*
Y325125D01*
G02X329692Y325124I1510J-1D01*
G01Y321624D01*
G02X326672I-1510J0D01*
G37*
G36*
G01X302757Y315392D02*
Y318893D01*
G02X305777Y318892I1510J-1D01*
G01Y315392D01*
G02X302757I-1510J0D01*
G37*
G36*
G01X333083Y309084D02*
Y312585D01*
G02X336103Y312584I1510J-1D01*
G01Y309084D01*
G02X333083I-1510J0D01*
G37*
G36*
G01X306057Y302792D02*
Y306293D01*
G02X309077Y306292I1510J-1D01*
G01Y302792D01*
G02X306057I-1510J0D01*
G37*
G36*
G01X326672Y296477D02*
Y299978D01*
G02X329692Y299977I1510J-1D01*
G01Y296477D01*
G02X326672I-1510J0D01*
G37*
G36*
G01X302757Y290192D02*
Y293693D01*
G02X305777Y293692I1510J-1D01*
G01Y290192D01*
G02X302757I-1510J0D01*
G37*
G36*
G01X332597Y283854D02*
Y287355D01*
G02X335617Y287354I1510J-1D01*
G01Y283854D01*
G02X332597I-1510J0D01*
G37*
G36*
G01X306057Y277592D02*
Y281093D01*
G02X309077Y281092I1510J-1D01*
G01Y277592D01*
G02X306057I-1510J0D01*
G37*
G36*
G01X303038Y265008D02*
Y268509D01*
G02X306058Y268508I1510J-1D01*
G01Y265008D01*
G02X303038I-1510J0D01*
G37*
G36*
G01X805747Y555869D02*
X805750Y555872D01*
X808119Y558240D01*
X808122Y558244D01*
G02X810250Y556128I1115J-1007D01*
G01X807872Y553750D01*
G02X805747Y555869I-1109J1013D01*
G37*
G36*
G01X787247D02*
X787250Y555872D01*
X789619Y558240D01*
X789622Y558244D01*
G02X791750Y556128I1115J-1007D01*
G01X789372Y553750D01*
G02X787247Y555869I-1109J1013D01*
G37*
G36*
G01X796747Y555369D02*
X796750Y555372D01*
X799119Y557740D01*
X799122Y557744D01*
G02X801250Y555628I1115J-1007D01*
G01X798872Y553250D01*
G02X796747Y555369I-1109J1013D01*
G37*
G36*
G01X777747Y554869D02*
X777750Y554872D01*
X780119Y557240D01*
X780122Y557244D01*
G02X782250Y555128I1115J-1007D01*
G01X779872Y552750D01*
G02X777747Y554869I-1109J1013D01*
G37*
G36*
G01X824247Y554369D02*
X824250Y554372D01*
X826619Y556740D01*
X826622Y556744D01*
G02X828750Y554628I1115J-1007D01*
G01X826372Y552250D01*
G02X824247Y554369I-1109J1013D01*
G37*
G36*
G01X767247Y553869D02*
X767250Y553872D01*
X769619Y556240D01*
X769622Y556244D01*
G02X771750Y554128I1115J-1007D01*
G01X769372Y551750D01*
G02X767247Y553869I-1109J1013D01*
G37*
G36*
G01X689685Y553463D02*
X687307Y551085D01*
G02X685182Y553204I-1109J1013D01*
G01X685185Y553207D01*
X687554Y555575D01*
X687557Y555579D01*
G02X689685Y553463I1115J-1007D01*
G37*
G36*
G01X707666Y552952D02*
X707669Y552955D01*
X710038Y555323D01*
X710041Y555327D01*
G02X712169Y553211I1115J-1007D01*
G01X709791Y550833D01*
G02X707666Y552952I-1109J1013D01*
G37*
G36*
G01X698437Y552184D02*
X698440Y552187D01*
X700809Y554555D01*
X700812Y554559D01*
G02X702940Y552443I1115J-1007D01*
G01X700562Y550065D01*
G02X698437Y552184I-1109J1013D01*
G37*
G36*
G01X727666Y551052D02*
X727669Y551055D01*
X730038Y553423D01*
X730041Y553427D01*
G02X732169Y551311I1115J-1007D01*
G01X729791Y548933D01*
G02X727666Y551052I-1109J1013D01*
G37*
G36*
G01X716813Y550962D02*
X716816Y550965D01*
X719185Y553333D01*
X719188Y553337D01*
G02X721316Y551221I1115J-1007D01*
G01X718938Y548843D01*
G02X716813Y550962I-1109J1013D01*
G37*
G36*
G01X811747Y549369D02*
X811750Y549372D01*
X814119Y551740D01*
X814122Y551744D01*
G02X816250Y549628I1115J-1007D01*
G01X813872Y547250D01*
G02X811747Y549369I-1109J1013D01*
G37*
G36*
G01X755247D02*
X755250Y549372D01*
X757619Y551740D01*
X757622Y551744D01*
G02X759750Y549628I1115J-1007D01*
G01X757372Y547250D01*
G02X755247Y549369I-1109J1013D01*
G37*
G36*
G01X838879Y547866D02*
X838882Y547869D01*
X841251Y550237D01*
X841254Y550241D01*
G02X843382Y548125I1115J-1007D01*
G01X841004Y545747D01*
G02X838879Y547866I-1109J1013D01*
G37*
G36*
G01X674511Y545936D02*
X672133Y543558D01*
G02X670008Y545677I-1109J1013D01*
G01X670011Y545680D01*
X672380Y548048D01*
X672383Y548052D01*
G02X674511Y545936I1115J-1007D01*
G37*
G36*
G01X683802Y544118D02*
X683805Y544121D01*
X686174Y546489D01*
X686177Y546493D01*
G02X688305Y544377I1115J-1007D01*
G01X685927Y541999D01*
G02X683802Y544118I-1109J1013D01*
G37*
G36*
G01X661408Y540365D02*
X659030Y537987D01*
G02X656905Y540106I-1109J1013D01*
G01X656908Y540109D01*
X659277Y542477D01*
X659280Y542481D01*
G02X661408Y540365I1115J-1007D01*
G37*
G36*
G01X723963Y522019D02*
X720609D01*
G02Y525019I-73J1500D01*
G01X723963D01*
G02Y522019I73J-1500D01*
G37*
G36*
G01X170252Y590302D02*
X146278D01*
X146223Y590190D01*
G02X143529I-1347J664D01*
G01X143474Y590302D01*
X125784D01*
X113071Y603015D01*
X113024Y603030D01*
G02X111568Y604486I648J2104D01*
G01X111553Y604533D01*
X110484Y605602D01*
Y635772D01*
X121010Y646298D01*
X120978Y646410D01*
G02X123690Y649122I2122J590D01*
G01X123802Y649090D01*
X127974Y653262D01*
X257111D01*
X311050Y599323D01*
Y546189D01*
X284574Y519713D01*
G02X284047Y519490I-538J537D01*
G02X284037I-5J750D01*
G01X159563D01*
G02X159026Y519713I1J760D01*
G01X144274Y534465D01*
Y554126D01*
X147574Y557426D01*
X172406D01*
X174035Y559055D01*
X174045Y559069D01*
G02X174396Y559420I1151J-800D01*
G01X174410Y559430D01*
X175080Y560100D01*
Y569584D01*
X173126Y571538D01*
X152611D01*
X106622Y525549D01*
X69018D01*
X59140Y535427D01*
Y551039D01*
X60869Y552768D01*
X63771D01*
X66137Y550402D01*
Y542807D01*
X66145Y542780D01*
G02Y541952I-1444J-414D01*
G01X66137Y541925D01*
Y534918D01*
X70922Y530133D01*
X104648D01*
X150601Y576086D01*
X169336D01*
X169608Y576358D01*
Y581354D01*
X170884Y582630D01*
X173074D01*
X175080Y584636D01*
Y586619D01*
X172981Y588718D01*
G02X170650Y589871I-933J1046D01*
G03X170252Y590302I-399J31D01*
G37*
G36*
G01X872689Y267246D02*
X831361D01*
X831142Y267465D01*
Y267466D01*
X791299Y307309D01*
G02X791079Y307839I530J531D01*
G01Y333427D01*
X790923Y333463D01*
G02Y338537I577J2537D01*
G01X791079Y338573D01*
Y449157D01*
X789630Y450606D01*
X677628D01*
G02X677098Y450826I1J750D01*
G01X670920Y457004D01*
G02X670700Y457534I530J531D01*
G01Y494630D01*
X675076Y499006D01*
X686381D01*
X702551Y515175D01*
G02X703081Y515395I531J-530D01*
G01X739917D01*
X745865Y521343D01*
X776736D01*
X783958Y514121D01*
X833981D01*
X836912Y517052D01*
X847730D01*
X854353Y510429D01*
Y325360D01*
X876847Y302866D01*
Y271058D01*
X873282Y267493D01*
X873280Y267490D01*
G02X873231Y267443I-544J519D01*
G01X873227Y267439D01*
X873035Y267246D01*
X872758D01*
G02X872689I-34J751D01*
G37*
G36*
G01X554379Y169072D02*
X554388Y169100D01*
Y173420D01*
X554379Y173448D01*
G02X558219I1920J568D01*
G01X558210Y173420D01*
Y169100D01*
X558219Y169072D01*
G02X554379I-1920J-568D01*
G37*
G36*
G01X526033D02*
X526042Y169100D01*
Y173420D01*
X526033Y173448D01*
G02X529873I1920J568D01*
G01X529864Y173420D01*
Y169100D01*
X529873Y169072D01*
G02X526033I-1920J-568D01*
G37*
G36*
G01X469340D02*
X469348Y169100D01*
Y173420D01*
X469340Y173448D01*
G02X473180I1920J568D01*
G01X473172Y173420D01*
Y169100D01*
X473180Y169072D01*
G02X469340I-1920J-568D01*
G37*
G36*
G01X547292Y145450D02*
X547300Y145478D01*
Y149798D01*
X547292Y149826D01*
G02X551132I1920J568D01*
G01X551124Y149798D01*
Y145478D01*
X551132Y145450D01*
G02X547292I-1920J-568D01*
G37*
G36*
G01X533119D02*
X533128Y145478D01*
Y149798D01*
X533119Y149826D01*
G02X536959I1920J568D01*
G01X536950Y149798D01*
Y145478D01*
X536959Y145450D01*
G02X533119I-1920J-568D01*
G37*
G36*
G01X518946D02*
X518954Y145478D01*
Y149798D01*
X518946Y149826D01*
G02X522786I1920J568D01*
G01X522778Y149798D01*
Y145478D01*
X522786Y145450D01*
G02X518946I-1920J-568D01*
G37*
G36*
G01X504773D02*
X504782Y145478D01*
Y149798D01*
X504773Y149826D01*
G02X508613I1920J568D01*
G01X508604Y149798D01*
Y145478D01*
X508613Y145450D01*
G02X504773I-1920J-568D01*
G37*
G36*
G01X462253D02*
X462262Y145478D01*
Y149798D01*
X462253Y149826D01*
G02X466093I1920J568D01*
G01X466084Y149798D01*
Y145478D01*
X466093Y145450D01*
G02X462253I-1920J-568D01*
G37*
G36*
G01X448080D02*
X448088Y145478D01*
Y149798D01*
X448080Y149826D01*
G02X451920I1920J568D01*
G01X451912Y149798D01*
Y145478D01*
X451920Y145450D01*
G02X448080I-1920J-568D01*
G37*
G36*
G01X433907D02*
X433916Y145478D01*
Y149798D01*
X433907Y149826D01*
G02X437747I1920J568D01*
G01X437738Y149798D01*
Y145478D01*
X437747Y145450D01*
G02X433907I-1920J-568D01*
G37*
G36*
G01X419733D02*
X419742Y145478D01*
Y149798D01*
X419733Y149826D01*
G02X423573I1920J568D01*
G01X423564Y149798D01*
Y145478D01*
X423573Y145450D01*
G02X419733I-1920J-568D01*
G37*
G36*
G01X554379Y140726D02*
X554388Y140754D01*
Y145074D01*
X554379Y145102D01*
G02X558219I1920J568D01*
G01X558210Y145074D01*
Y140754D01*
X558219Y140726D01*
G02X554379I-1920J-568D01*
G37*
G36*
G01X540206D02*
X540214Y140754D01*
Y145074D01*
X540206Y145102D01*
G02X544046I1920J568D01*
G01X544038Y145074D01*
Y140754D01*
X544046Y140726D01*
G02X540206I-1920J-568D01*
G37*
G36*
G01X526033D02*
X526042Y140754D01*
Y145074D01*
X526033Y145102D01*
G02X529873I1920J568D01*
G01X529864Y145074D01*
Y140754D01*
X529873Y140726D01*
G02X526033I-1920J-568D01*
G37*
G36*
G01X511859D02*
X511868Y140754D01*
Y145074D01*
X511859Y145102D01*
G02X515699I1920J568D01*
G01X515690Y145074D01*
Y140754D01*
X515699Y140726D01*
G02X511859I-1920J-568D01*
G37*
G36*
G01X469340D02*
X469348Y140754D01*
Y145074D01*
X469340Y145102D01*
G02X473180I1920J568D01*
G01X473172Y145074D01*
Y140754D01*
X473180Y140726D01*
G02X469340I-1920J-568D01*
G37*
G36*
G01X455166D02*
X455174Y140754D01*
Y145074D01*
X455166Y145102D01*
G02X459006I1920J568D01*
G01X458998Y145074D01*
Y140754D01*
X459006Y140726D01*
G02X455166I-1920J-568D01*
G37*
G36*
G01X440993D02*
X441002Y140754D01*
Y145074D01*
X440993Y145102D01*
G02X444833I1920J568D01*
G01X444824Y145074D01*
Y140754D01*
X444833Y140726D01*
G02X440993I-1920J-568D01*
G37*
G36*
G01X426820D02*
X426828Y140754D01*
Y145074D01*
X426820Y145102D01*
G02X430660I1920J568D01*
G01X430652Y145074D01*
Y140754D01*
X430660Y140726D01*
G02X426820I-1920J-568D01*
G37*
G36*
G01X547292Y131277D02*
X547300Y131305D01*
Y135625D01*
X547292Y135653D01*
G02X551132I1920J568D01*
G01X551124Y135625D01*
Y131305D01*
X551132Y131277D01*
G02X547292I-1920J-568D01*
G37*
G36*
G01X533119D02*
X533128Y131305D01*
Y135625D01*
X533119Y135653D01*
G02X536959I1920J568D01*
G01X536950Y135625D01*
Y131305D01*
X536959Y131277D01*
G02X533119I-1920J-568D01*
G37*
G36*
G01X518946D02*
X518954Y131305D01*
Y135625D01*
X518946Y135653D01*
G02X522786I1920J568D01*
G01X522778Y135625D01*
Y131305D01*
X522786Y131277D01*
G02X518946I-1920J-568D01*
G37*
G36*
G01X504773D02*
X504782Y131305D01*
Y135625D01*
X504773Y135653D01*
G02X508613I1920J568D01*
G01X508604Y135625D01*
Y131305D01*
X508613Y131277D01*
G02X504773I-1920J-568D01*
G37*
G36*
G01X462253D02*
X462262Y131305D01*
Y135625D01*
X462253Y135653D01*
G02X466093I1920J568D01*
G01X466084Y135625D01*
Y131305D01*
X466093Y131277D01*
G02X462253I-1920J-568D01*
G37*
G36*
G01X448080D02*
X448088Y131305D01*
Y135625D01*
X448080Y135653D01*
G02X451920I1920J568D01*
G01X451912Y135625D01*
Y131305D01*
X451920Y131277D01*
G02X448080I-1920J-568D01*
G37*
G36*
G01X433907D02*
X433916Y131305D01*
Y135625D01*
X433907Y135653D01*
G02X437747I1920J568D01*
G01X437738Y135625D01*
Y131305D01*
X437747Y131277D01*
G02X433907I-1920J-568D01*
G37*
G36*
G01X419733D02*
X419742Y131305D01*
Y135625D01*
X419733Y135653D01*
G02X423573I1920J568D01*
G01X423564Y135625D01*
Y131305D01*
X423573Y131277D01*
G02X419733I-1920J-568D01*
G37*
G36*
G01X554379Y126553D02*
X554388Y126581D01*
Y130900D01*
X554379Y130928D01*
G02X558219I1920J568D01*
G01X558210Y130900D01*
Y126581D01*
X558219Y126553D01*
G02X554379I-1920J-568D01*
G37*
G36*
G01X540206D02*
X540214Y126581D01*
Y130900D01*
X540206Y130928D01*
G02X544046I1920J568D01*
G01X544038Y130900D01*
Y126581D01*
X544046Y126553D01*
G02X540206I-1920J-568D01*
G37*
G36*
G01X526033D02*
X526042Y126581D01*
Y130900D01*
X526033Y130928D01*
G02X529873I1920J568D01*
G01X529864Y130900D01*
Y126581D01*
X529873Y126553D01*
G02X526033I-1920J-568D01*
G37*
G36*
G01X511859D02*
X511868Y126581D01*
Y130900D01*
X511859Y130928D01*
G02X515699I1920J568D01*
G01X515690Y130900D01*
Y126581D01*
X515699Y126553D01*
G02X511859I-1920J-568D01*
G37*
G36*
G01X469340D02*
X469348Y126581D01*
Y130900D01*
X469340Y130928D01*
G02X473180I1920J568D01*
G01X473172Y130900D01*
Y126581D01*
X473180Y126553D01*
G02X469340I-1920J-568D01*
G37*
G36*
G01X455166D02*
X455174Y126581D01*
Y130900D01*
X455166Y130928D01*
G02X459006I1920J568D01*
G01X458998Y130900D01*
Y126581D01*
X459006Y126553D01*
G02X455166I-1920J-568D01*
G37*
G36*
G01X440993D02*
X441002Y126581D01*
Y130900D01*
X440993Y130928D01*
G02X444833I1920J568D01*
G01X444824Y130900D01*
Y126581D01*
X444833Y126553D01*
G02X440993I-1920J-568D01*
G37*
G36*
G01X426820D02*
X426828Y126581D01*
Y130900D01*
X426820Y130928D01*
G02X430660I1920J568D01*
G01X430652Y130900D01*
Y126581D01*
X430660Y126553D01*
G02X426820I-1920J-568D01*
G37*
G36*
G01X509945Y101692D02*
X505815D01*
G02Y104696I-36J1502D01*
G01X509945D01*
G02Y101692I36J-1502D01*
G37*
G54D54*
X305906Y182874D03*
G54D53*
X201801Y684252D03*
X225601D03*
G54D55*
X305906Y388386D03*
G54D58*
X666929Y510236D03*
G54D43*
X811024Y24409D03*
G54D44*
X103346Y34449D03*
X56102Y24606D03*
G54D46*
X706299Y201771D03*
Y83661D03*
G54D45*
X804724Y201772D03*
Y83661D03*
G54D50*
X34652Y111485D03*
X33297Y703990D03*
X899219Y47960D03*
G54D56*
X488838Y137225D03*
G54D57*
Y164744D03*
G54D51*
X90157Y413582D03*
X309055Y157677D03*
G54D47*
X309252Y413583D03*
G54D48*
X89764Y238386D03*
G54D49*
X70866Y98425D03*
Y472441D03*
X314961D03*
X875984Y31496D03*
Y472441D03*
Y606299D03*
G54D52*
X163189Y669291D03*
%LPC*%
G75*
G36*
G01X175080Y578659D02*
X174932Y578619D01*
G03Y575913I366J-1353D01*
G01X175080Y575873D01*
Y574984D01*
X173134Y573038D01*
X151989D01*
X106000Y527049D01*
X69640D01*
X60640Y536049D01*
Y550417D01*
X61491Y551268D01*
X63149D01*
X64637Y549780D01*
Y543876D01*
X64468Y543850D01*
G03Y540882I233J-1484D01*
G01X64637Y540856D01*
Y534296D01*
X70300Y528633D01*
X105270D01*
X151223Y574586D01*
X169958D01*
X171108Y575736D01*
Y580732D01*
X171506Y581130D01*
X173038D01*
X175080Y579088D01*
Y578659D01*
G37*
G36*
G01X176580Y559478D02*
Y576697D01*
X176595Y576734D01*
G03Y577798I-1297J532D01*
G01X176580Y577835D01*
Y587241D01*
X172238Y591582D01*
G03X171708Y591802I-531J-530D01*
G01X146041D01*
G03X143711I-1165J-948D01*
G01X126406D01*
X111984Y606224D01*
Y635150D01*
X121950Y645116D01*
X122080Y645048D01*
G03X125052Y648020I1020J1952D01*
G01X124984Y648150D01*
X128596Y651762D01*
X256489D01*
X309550Y598701D01*
Y546811D01*
X283729Y520990D01*
X175791D01*
G03X173009I-1391J-1707D01*
G01X159871D01*
X145774Y535087D01*
Y553504D01*
X148196Y555926D01*
X173028D01*
X174289Y557187D01*
X174425Y557098D01*
G03X176367Y559040I771J1171D01*
G01X176278Y559176D01*
X176580Y559478D01*
G37*
G36*
G01X852853Y324738D02*
X875347Y302244D01*
Y271680D01*
X872413Y268746D01*
X831983D01*
X792579Y308150D01*
Y315314D01*
X792585Y315338D01*
G03Y316632I-2520J647D01*
G01X792579Y316656D01*
Y325314D01*
X792585Y325338D01*
G03Y326632I-2520J647D01*
G01X792579Y326656D01*
Y333632D01*
G03Y338368I-1079J2368D01*
G01Y345314D01*
X792585Y345338D01*
G03Y346632I-2520J647D01*
G01X792579Y346656D01*
Y355314D01*
X792585Y355338D01*
G03Y356632I-2520J647D01*
G01X792579Y356656D01*
Y365314D01*
X792585Y365338D01*
G03Y366632I-2520J647D01*
G01X792579Y366656D01*
Y375314D01*
X792585Y375338D01*
G03Y376632I-2520J647D01*
G01X792579Y376656D01*
Y395314D01*
X792585Y395338D01*
G03Y396632I-2520J647D01*
G01X792579Y396656D01*
Y405314D01*
X792585Y405338D01*
G03Y406632I-2520J647D01*
G01X792579Y406656D01*
Y415314D01*
X792585Y415338D01*
G03Y416632I-2520J647D01*
G01X792579Y416656D01*
Y425453D01*
G03Y427519I-2388J1033D01*
G01Y435314D01*
X792585Y435338D01*
G03Y436632I-2520J647D01*
G01X792579Y436656D01*
Y445314D01*
X792585Y445338D01*
G03Y446632I-2520J647D01*
G01X792579Y446656D01*
Y449468D01*
G03X792359Y449998I-750J-1D01*
G01X790471Y451886D01*
G03X789941Y452106I-531J-530D01*
G01X677939D01*
X672200Y457845D01*
Y494008D01*
X675698Y497506D01*
X687003D01*
X703392Y513895D01*
X740539D01*
X746487Y519843D01*
X776114D01*
X783336Y512621D01*
X834603D01*
X837534Y515552D01*
X847108D01*
X852853Y509807D01*
Y324738D01*
G37*
%LPD*%
G75*
G54D58*
X765354Y510236D03*
G54D59*
X745669D03*
X844094D03*
G54D28*
X339331Y49803D03*
X360669Y91929D03*
G54D12*
X38500Y56500D03*
X46500Y48500D03*
X28123Y453658D03*
X64427Y538836D03*
X61100Y546700D03*
X67852Y539219D03*
X67853Y564416D03*
Y554967D03*
Y542368D03*
X64701Y561266D03*
X63456Y555041D03*
X67853Y561266D03*
X64701Y542366D03*
X64151Y521695D03*
X53524Y521269D03*
Y526995D03*
Y532622D03*
X52613Y538242D03*
X52408Y543876D03*
X52603Y549526D03*
X52485Y555153D03*
X53300Y560879D03*
X67853Y577015D03*
X64703Y586463D03*
X64701Y567566D03*
X67853Y570715D03*
X53302Y567317D03*
X58926Y582407D03*
X28667Y634097D03*
X42550Y599224D03*
X56100Y676000D03*
X86268Y58755D03*
X78268Y66755D03*
X121233Y450900D03*
X108500Y475500D03*
X97074Y492891D03*
X112722Y493971D03*
X98400Y473200D03*
X140490Y488605D03*
X132777Y462639D03*
X130787Y479138D03*
X113300Y448564D03*
X118065Y448535D03*
X100600Y490750D03*
X138023Y456188D03*
X140985Y454250D03*
X135262Y475726D03*
X74151Y545516D03*
X86750Y542368D03*
X126337Y554085D03*
X74498Y551757D03*
X130311Y546700D03*
X71002Y539219D03*
X81276Y548766D03*
X119605Y548705D03*
X86750Y539218D03*
X74076Y535966D03*
X83600Y545518D03*
X75508Y542198D03*
X89899Y545518D03*
X127300Y543200D03*
X71002Y542368D03*
X117200Y546300D03*
X89899Y539218D03*
X83600Y539219D03*
X71002Y545518D03*
X86750D03*
X122600Y557480D03*
X71002Y558117D03*
X86750Y554965D03*
Y558115D03*
X83600Y551817D03*
X71002Y564396D03*
Y561266D03*
X83600Y564415D03*
X86750D03*
X75066Y563235D03*
X83600Y561265D03*
X71002Y554967D03*
X86750Y551815D03*
X123300Y530300D03*
X119400Y521700D03*
X133800Y528500D03*
X102601Y507300D03*
X123200Y534600D03*
X78276Y545566D03*
X93744Y542019D03*
X133554Y537374D03*
X71002Y548668D03*
X92600Y535623D03*
X86750Y561265D03*
X89899D03*
X94720Y557158D03*
X92286Y521695D03*
X86659D03*
X81032D03*
X75405D03*
X69778D03*
X97913D03*
X96371Y534124D03*
X125400Y498600D03*
X140400Y607850D03*
X137000D03*
X130700D03*
X135706Y621187D03*
X119900Y621000D03*
X131200Y620600D03*
X130607Y569636D03*
X126347Y569556D03*
X117400Y567650D03*
X83600Y573865D03*
X74152Y567565D03*
X86750Y586463D03*
X71002Y567565D03*
X86750Y583313D03*
X74152Y580163D03*
X83601Y580164D03*
X89899Y577014D03*
X74152Y577013D03*
X86750Y577014D03*
X96570Y581730D03*
X118900Y609900D03*
X116400Y626600D03*
X124903Y613900D03*
X124793Y617299D03*
X139500Y611200D03*
X138970Y632277D03*
X74152Y583312D03*
X94011Y597066D03*
X101608Y596523D03*
X93048Y580164D03*
X89899Y567565D03*
X93049Y573864D03*
X93051Y587466D03*
X83600Y567565D03*
X128700Y615500D03*
X138700Y636655D03*
X103098Y620264D03*
X98537Y601094D03*
X102509Y601100D03*
X103109Y608572D03*
X103124Y605153D03*
X103098Y612064D03*
Y624364D03*
X113672Y605134D03*
X113512Y613401D03*
X113426Y609234D03*
X108137Y615870D03*
X113400Y621400D03*
Y617400D03*
X70700Y629000D03*
X133835Y609620D03*
X127100Y647000D03*
X123100D03*
X86028Y696439D03*
X81928Y697539D03*
X106879Y707245D03*
X125376Y701124D03*
X106635Y701465D03*
X94106Y699683D03*
X89868Y689124D03*
X121300Y651900D03*
X139774Y666686D03*
X119849Y709715D03*
X106355Y710745D03*
X143700Y469000D03*
X188708Y468154D03*
X175115Y463761D03*
X167821Y488301D03*
X208370Y491570D03*
X200260Y465900D03*
X211324Y489886D03*
X167656Y465300D03*
X189700Y463500D03*
X181200Y489451D03*
X155710Y485200D03*
X172300Y478400D03*
X172900Y484101D03*
X169252Y483871D03*
X213159Y460326D03*
X154334Y465100D03*
X149000Y488600D03*
X171537Y464400D03*
X179100Y455800D03*
X201600Y486500D03*
X198200D03*
X190036Y485520D03*
X194411Y485447D03*
X163031Y441700D03*
X193400Y463300D03*
X153489Y481559D03*
X148490Y451286D03*
X144245Y452344D03*
X151877Y450439D03*
X155877D03*
X145000Y488600D03*
X167680Y510640D03*
X166761Y498900D03*
X188600Y531500D03*
X208700Y529100D03*
X187500Y523700D03*
X154730Y512704D03*
X158241Y512675D03*
X170700Y513600D03*
X182870Y513832D03*
X212300Y529000D03*
X141980Y508590D03*
X146900Y512500D03*
X185615Y498015D03*
X174900Y499800D03*
X203610Y529397D03*
X179400Y525100D03*
X182964Y510414D03*
X154400Y533500D03*
X187100Y509600D03*
X195200Y513200D03*
X162537Y499000D03*
X160286Y508429D03*
X183750Y524200D03*
X143415Y530143D03*
X171200Y509840D03*
X170800Y499800D03*
X166600Y524100D03*
X144087Y526413D03*
X176900Y496500D03*
X174717Y524010D03*
X178869Y509793D03*
X200650Y497862D03*
X199501Y509275D03*
X174700Y509600D03*
X207500Y505812D03*
X158000Y499000D03*
X200200Y529200D03*
X156000Y496100D03*
X203696Y533000D03*
X156200Y535800D03*
X188834Y496920D03*
X190929Y512592D03*
X150553Y512500D03*
X148050Y523740D03*
X196800Y497862D03*
X193200Y497000D03*
X174400Y519283D03*
X200963Y636600D03*
X212923Y615000D03*
X191210Y617900D03*
X203300Y628900D03*
X148409Y575672D03*
X144876Y590854D03*
X148409Y579353D03*
X144876Y587173D03*
X185100Y614300D03*
X179700Y615300D03*
X151800Y615400D03*
X197611Y630698D03*
X193400Y630600D03*
X174799Y630303D03*
X171400Y630200D03*
X199950Y614000D03*
X196100Y614050D03*
X203900Y614100D03*
X144737Y630882D03*
X200100Y633300D03*
X209193Y614249D03*
X162750Y612217D03*
X164400Y609200D03*
X182100Y629800D03*
X178200D03*
X148210Y629830D03*
X141742Y624666D03*
X144263Y609023D03*
X151800Y610300D03*
X188899Y629597D03*
X185500Y629700D03*
X154500Y629600D03*
X195600Y646000D03*
X166500Y640300D03*
X211706Y645349D03*
X208200Y645500D03*
X184807Y643963D03*
X205827Y695000D03*
X188600Y696800D03*
X159058Y641132D03*
X142572Y640332D03*
X150872D03*
X177100Y640400D03*
X173000D03*
X193400Y639700D03*
X189500D03*
X185300D03*
X181000D03*
X198700D03*
X151949Y691715D03*
X176447Y704925D03*
X162700Y703500D03*
X150849Y710215D03*
X162360Y706888D03*
X168273Y696434D03*
X158994Y694545D03*
X205800Y698400D03*
X210123Y662100D03*
X200000Y664200D03*
X204100Y646500D03*
X199600Y646300D03*
X195500Y696900D03*
X207000Y654400D03*
X185598Y709274D03*
X182200Y709400D03*
X143174Y666586D03*
X162100Y711215D03*
X275276Y494017D03*
X275700Y490300D03*
X275100Y472400D03*
X264800Y467400D03*
X278800Y467500D03*
X277455Y446150D03*
X226475Y480400D03*
X254100Y440800D03*
X257950Y440600D03*
X226500Y477000D03*
X275113Y476513D03*
X266664Y493000D03*
X214808Y463300D03*
X231400Y489800D03*
X237903D03*
X267670Y485870D03*
X271100Y485900D03*
X222995Y443805D03*
X240900Y440900D03*
X236400Y440800D03*
X280600Y448900D03*
X214900Y490000D03*
X231476Y449662D03*
X276591Y483709D03*
X245874Y458478D03*
X242500Y458900D03*
X253400Y453500D03*
X273400Y449700D03*
X249465Y458000D03*
X252626Y469150D03*
X244400Y478600D03*
X244300Y474150D03*
X225532Y450047D03*
X237600Y455500D03*
X233664Y482859D03*
X226607Y444058D03*
X230610Y444055D03*
X234648Y540453D03*
X222500Y536161D03*
X279600Y527900D03*
X272100Y537500D03*
X251346Y554100D03*
X256816Y563982D03*
X262996Y548757D03*
X231450Y563000D03*
X270021Y549394D03*
X283600Y539294D03*
X242700Y548600D03*
X252400Y539600D03*
X271715Y556690D03*
X263400Y531500D03*
X233850Y552201D03*
X234943Y565199D03*
X260513Y564135D03*
X265100Y562300D03*
X227600Y563000D03*
X254494Y529198D03*
X248459Y523892D03*
X269100Y509063D03*
X244850Y540150D03*
X248700Y540000D03*
X228200Y496200D03*
X263600Y540700D03*
X226357Y504514D03*
X257894Y529254D03*
X263600Y535350D03*
X223800Y531600D03*
X236400Y502150D03*
X246508Y532821D03*
X228100Y545500D03*
X227100Y525400D03*
X228800Y542100D03*
X238600Y509900D03*
X228313Y552169D03*
X233100Y509800D03*
X275100D03*
X260900Y553900D03*
X242600Y509800D03*
X233607Y557671D03*
X241154Y536017D03*
X250445Y548551D03*
X255800Y539600D03*
X279200Y531600D03*
X250400Y636976D03*
X215800Y631200D03*
X260705Y598359D03*
X232896Y613795D03*
X279450Y577970D03*
X260850Y603537D03*
X274800Y607500D03*
X258600Y613100D03*
X254208Y603995D03*
X254043Y598359D03*
X247088Y610236D03*
X254821Y627000D03*
X255228Y631071D03*
X229800Y593200D03*
X246800Y589600D03*
X261900Y588900D03*
X245400Y581800D03*
X264358Y608152D03*
X241300Y635900D03*
X228900Y635800D03*
X222500Y630200D03*
X218800Y635600D03*
X225900Y615000D03*
X221800Y614800D03*
X246500Y602500D03*
X234000Y628400D03*
X230900Y581600D03*
X270300Y622315D03*
X281500Y598419D03*
X231200Y576800D03*
X234700Y581600D03*
X254408Y586483D03*
X255400Y579500D03*
X225900Y630988D03*
X230063Y618667D03*
X274100Y591000D03*
X279745Y608000D03*
X255663Y617763D03*
X276376Y574132D03*
X281636Y588796D03*
X231000Y571900D03*
X242333Y593800D03*
X257346Y599169D03*
X257332Y602569D03*
X258398Y605915D03*
Y609484D03*
X218200Y609500D03*
X262694Y568076D03*
X261300Y571300D03*
X235800Y615100D03*
X233447Y603747D03*
X232300Y600300D03*
X258596Y586356D03*
X259848Y583194D03*
X279214Y591383D03*
X275652Y577455D03*
X237100Y590000D03*
X234087Y618038D03*
X248800Y582000D03*
X273022Y580751D03*
X268200Y578700D03*
X259000Y617000D03*
X234800Y572000D03*
X256007Y575050D03*
X281975Y572963D03*
X279800Y569182D03*
X264200Y574100D03*
X261810Y633980D03*
X264800Y632300D03*
X276783Y588907D03*
X258873Y631373D03*
X215400Y626800D03*
X281510Y583003D03*
X276400Y700650D03*
X254900Y701950D03*
X245100Y639500D03*
X219200Y645300D03*
X230270Y645933D03*
X223013Y645672D03*
X231500Y659100D03*
X255050Y675750D03*
X271240Y698960D03*
X243731Y709100D03*
X272900Y669100D03*
X254600Y685100D03*
X278150Y648363D03*
X284000Y678300D03*
X263800Y648902D03*
X236000Y646100D03*
X272300Y665700D03*
X266398Y679250D03*
X226708Y645869D03*
X239400Y677600D03*
X267045Y695881D03*
X215606Y645300D03*
X277600Y680200D03*
X217638Y695562D03*
X239000Y691000D03*
X276400Y697250D03*
X254700Y708900D03*
X271220Y679910D03*
X255000Y679900D03*
X235042Y656173D03*
X263500Y643212D03*
X243100Y677500D03*
X267100Y699700D03*
X266400Y662200D03*
X254648Y745463D03*
X268520Y719420D03*
X258431Y712169D03*
X268230Y723570D03*
X340706Y128612D03*
X352000Y109000D03*
X355500D03*
X305651Y199283D03*
X294720Y182200D03*
X320700Y177800D03*
X294720Y178600D03*
Y185600D03*
X307567Y277592D03*
X304548Y268508D03*
Y265008D03*
X335100Y228117D03*
X333882Y273978D03*
Y270578D03*
X335098Y233078D03*
X305782Y230874D03*
X334482Y263778D03*
X333782Y267178D03*
X324000Y222800D03*
X305782Y220674D03*
X305682Y224074D03*
X305782Y217274D03*
X334198Y248824D03*
X305454Y244461D03*
X334282Y252378D03*
X305373Y251101D03*
X306412Y254339D03*
X334260Y255820D03*
X305882Y234274D03*
X305772Y237673D03*
X305781Y241076D03*
X334107Y287354D03*
Y283854D03*
X304267Y344092D03*
Y340592D03*
X307567Y331492D03*
Y327992D03*
X304267Y318892D03*
Y315392D03*
X307567Y306292D03*
Y302792D03*
X304267Y293692D03*
Y290192D03*
X334582Y337721D03*
Y334221D03*
X328187Y350316D03*
Y346816D03*
X328182Y325124D03*
Y321624D03*
X334593Y312584D03*
Y309084D03*
X328182Y299977D03*
Y296477D03*
X307567Y281092D03*
X304267Y369292D03*
Y365792D03*
X307567Y356692D03*
Y353192D03*
X328182Y375518D03*
Y372018D03*
X334582Y362974D03*
Y359474D03*
X336000Y384400D03*
X336230Y377800D03*
X350408Y393708D03*
X348006Y391300D03*
X321859Y388315D03*
X321100Y384874D03*
X346300Y374600D03*
X349100Y379100D03*
X303900Y380574D03*
X348997Y491678D03*
X295700Y428400D03*
X293326Y494174D03*
X344900Y442800D03*
X344688Y493896D03*
X343050Y438900D03*
X339900Y454000D03*
X328313Y435513D03*
X324916Y435360D03*
X321700Y436650D03*
X296254Y546706D03*
X292200Y542473D03*
X285800Y549394D03*
X304800Y554443D03*
X285833Y557629D03*
X302700Y551300D03*
X339062Y521100D03*
X344600Y507600D03*
X341300Y536200D03*
X352921Y536521D03*
X311900Y514900D03*
X287500Y518000D03*
X297850Y524500D03*
X293600Y518400D03*
X288000Y561000D03*
X313300Y518800D03*
X354300Y500245D03*
X288311Y496200D03*
X355600Y506600D03*
X298200Y521100D03*
X301300Y524400D03*
X355600Y513500D03*
X327300Y540100D03*
X341400Y560050D03*
X336881Y530496D03*
X307800Y546700D03*
X341615Y556015D03*
X336953Y534506D03*
X305913Y549643D03*
X331900Y549700D03*
X329050Y552315D03*
X348220Y563836D03*
X344812Y563844D03*
X344755Y497841D03*
X304436Y564081D03*
X341349Y563750D03*
X307350Y561290D03*
X335000Y497000D03*
X332698Y543738D03*
X330200Y535200D03*
X331000Y522100D03*
X302665Y547006D03*
X302506Y543341D03*
X327403Y543499D03*
X336723Y542000D03*
X327800Y514900D03*
X330200Y531800D03*
X323400Y507540D03*
X336800Y506300D03*
X286061Y502378D03*
X293970Y564927D03*
X335000Y500600D03*
X298719Y542538D03*
X293500Y522600D03*
X334811Y551476D03*
X311900Y511500D03*
X309600Y520150D03*
X312300Y540600D03*
X332940Y539287D03*
X333400Y503800D03*
X322900Y530600D03*
X327417Y548344D03*
X290000Y503200D03*
X293800Y503300D03*
X299100Y589200D03*
X304124Y570227D03*
X307542Y588138D03*
X353500Y624500D03*
X353669Y600881D03*
X302300Y582000D03*
X286700Y611911D03*
X340920Y575234D03*
X348000Y612661D03*
X352472Y581000D03*
X325762Y596900D03*
X324900Y581600D03*
X291839Y578193D03*
X293697Y589566D03*
X289070Y573080D03*
X355700Y579317D03*
X341755Y627231D03*
Y623682D03*
X341600Y616962D03*
Y613413D03*
X334264Y602648D03*
X337813D03*
X352716Y594135D03*
X350746Y574837D03*
X293500Y625600D03*
X293600Y629100D03*
X321421Y605265D03*
X323413Y602491D03*
X303000Y586800D03*
X292006Y574797D03*
X315616Y571817D03*
X289800Y569182D03*
X315893Y567721D03*
X341558Y567689D03*
X352716Y590535D03*
X347784Y587509D03*
X336923Y586749D03*
X347784Y584109D03*
X336923Y583349D03*
X307650Y596000D03*
X285400Y572556D03*
X325761Y592959D03*
X315315Y575204D03*
X317813Y580469D03*
X286400Y569200D03*
X317813Y584969D03*
X325899Y589186D03*
X328356Y678679D03*
X297900Y664800D03*
X290600Y668200D03*
X338301Y673907D03*
X328600Y661100D03*
X343372Y655836D03*
X347013Y656090D03*
X328087Y701587D03*
X327062Y697600D03*
X332200Y643800D03*
X288720Y641455D03*
X289473Y657061D03*
X336000Y662200D03*
X336387Y648987D03*
X317516Y671612D03*
X315000Y674900D03*
X338135Y670511D03*
X342542Y685983D03*
X342645Y682506D03*
X300700Y667000D03*
X330593Y671019D03*
X303741Y654095D03*
X329989Y653920D03*
X291700Y737000D03*
X316465Y716063D03*
X287220Y737920D03*
X334000Y714640D03*
X293075Y726600D03*
X342208Y714950D03*
X337481Y719818D03*
X425765Y56265D03*
X372500Y44500D03*
Y56500D03*
X387833Y82930D03*
X391382D03*
X372500Y90000D03*
Y78000D03*
X396800Y74800D03*
X365800Y193750D03*
X399900Y152100D03*
X400924Y155896D03*
X404473D03*
X398000Y165400D03*
X398050Y162000D03*
X406400Y150300D03*
X363828Y243944D03*
X381009Y343909D03*
X380799Y347303D03*
X386250Y318250D03*
X380600Y335700D03*
X373700Y329700D03*
X376910Y366078D03*
X359323Y372277D03*
X363699Y382608D03*
X363703Y386008D03*
X363586Y375809D03*
X363701Y379208D03*
X377300Y362700D03*
X361250Y491650D03*
X363942Y450591D03*
X366700Y454800D03*
X359400Y451600D03*
X381276Y469106D03*
X374030Y449526D03*
X372575Y452600D03*
X380200Y457800D03*
X381400Y462000D03*
X387500Y458200D03*
X370800Y475128D03*
X389081Y475224D03*
X387950Y466800D03*
X394700Y481700D03*
X394952Y485300D03*
X378937Y443491D03*
X376697Y446050D03*
X373576Y466300D03*
X373534Y462830D03*
X370900Y471700D03*
X373700Y482700D03*
X378200Y476600D03*
X377691Y451891D03*
X381370Y465500D03*
X388123Y492432D03*
X378840Y448690D03*
X361013Y475128D03*
X372714Y509275D03*
X364000Y525500D03*
X387400Y547500D03*
X384400Y545195D03*
X362666Y504265D03*
X390651Y499000D03*
X387800Y525500D03*
X387700Y521600D03*
X376617Y544817D03*
X397650Y508250D03*
Y536671D03*
X362280Y554590D03*
X397650Y519400D03*
X394880Y548670D03*
X397650Y523900D03*
X393465Y553100D03*
X387700Y517700D03*
X362500Y499970D03*
X365730Y541050D03*
X368900Y505000D03*
X372494Y513020D03*
X383126Y565162D03*
X366490Y564360D03*
X370763Y547900D03*
X370800Y551300D03*
Y554700D03*
X383080Y554897D03*
X384347Y558647D03*
X382922Y561735D03*
X372900Y538700D03*
X396400Y545500D03*
X390769Y495379D03*
X393889Y543207D03*
X367133Y596067D03*
X382380Y612620D03*
X371180Y629236D03*
X386224Y580524D03*
X383411Y577024D03*
X362250Y570875D03*
X364300Y592900D03*
X384500Y616500D03*
X361227Y630300D03*
X378400Y594800D03*
X383313Y621780D03*
X365953Y570753D03*
X382600Y609000D03*
X375700Y580102D03*
X390600Y625500D03*
X366100Y590000D03*
X366500Y586300D03*
X380572Y592095D03*
X396300Y587000D03*
X396400Y583500D03*
X395127Y568056D03*
X395100Y572899D03*
X379100Y703300D03*
X363664Y688950D03*
X384466Y661650D03*
X378832Y659705D03*
X364600Y670800D03*
X388338Y643600D03*
Y647149D03*
X392100Y683900D03*
X392000Y679800D03*
X390500Y665800D03*
Y669200D03*
X396306Y698732D03*
X361914Y680181D03*
X401000Y676500D03*
X371457Y667593D03*
X368060Y667743D03*
X392079Y703434D03*
X396400Y659800D03*
X390355Y690926D03*
X373060Y702960D03*
X398600Y662700D03*
X383600Y711800D03*
X372100Y711700D03*
X478426Y20427D03*
X472800Y50000D03*
X469000Y50100D03*
X499721Y46102D03*
X499623Y49524D03*
X446788Y55180D03*
X479040Y47134D03*
X458041Y47341D03*
X476100Y60500D03*
X478700Y62800D03*
X462372Y49179D03*
X486400Y38500D03*
X467016Y20430D03*
X450454Y38147D03*
X486527Y41939D03*
X447233Y48829D03*
X496355Y26000D03*
X496242Y22287D03*
X460300Y57600D03*
X432269Y19980D03*
X486700Y31100D03*
X462874Y95922D03*
X487500Y73400D03*
X485700Y70500D03*
X448000Y80404D03*
X444800Y82404D03*
X478590Y70310D03*
X482200Y70500D03*
X498500Y84200D03*
X471281Y105681D03*
X455766Y114535D03*
X473600Y108300D03*
X457000Y117800D03*
X480538Y112071D03*
X459500Y95500D03*
X441100Y110950D03*
X448996Y117666D03*
X463479Y99412D03*
X504900Y18200D03*
X508646Y18386D03*
X515700Y50899D03*
X515785Y55552D03*
X505633Y46932D03*
X502300Y58200D03*
X531050Y46998D03*
X528300Y58648D03*
X515500Y59000D03*
X513500Y62000D03*
X532500Y58600D03*
X543059Y108958D03*
X540800Y111500D03*
X501100Y86800D03*
X538456Y65144D03*
X509981Y103194D03*
X505779D03*
X513300Y83000D03*
X503700Y107600D03*
X599254Y37967D03*
X582447Y50607D03*
X586754Y53967D03*
X577847Y50807D03*
X582797Y31807D03*
X600847Y33907D03*
X588753Y24080D03*
X636647Y64300D03*
X642998Y127863D03*
X642574Y131843D03*
X710550Y18550D03*
X685907Y30622D03*
X673647Y33107D03*
X680300Y17500D03*
X680000Y23900D03*
X675903Y29541D03*
X668531Y71500D03*
X713200Y387700D03*
X696070Y483486D03*
X712874Y470182D03*
X707391Y484208D03*
X712000Y442100D03*
X711300Y423800D03*
X701183Y453339D03*
X704836D03*
X709700Y480332D03*
X698651Y428165D03*
X669749Y458022D03*
X683000Y447200D03*
X680200Y449500D03*
X705450Y440950D03*
X705700Y493500D03*
X708367Y491000D03*
X708682Y551846D03*
X711156Y554320D03*
X699453Y551078D03*
X701927Y553552D03*
X686198Y552098D03*
X688672Y554572D03*
X684818Y543012D03*
X687292Y545486D03*
X671024Y544571D03*
X673498Y547045D03*
X657921Y539000D03*
X660395Y541474D03*
X653634Y513757D03*
X656846Y521702D03*
X678740Y508760D03*
X777500Y34500D03*
X718300Y387700D03*
X725200Y442100D03*
X740500Y431000D03*
X788263Y554763D03*
X778763Y553763D03*
X781237Y556237D03*
X768263Y552763D03*
X770737Y555237D03*
X756263Y548263D03*
X758737Y550737D03*
X728682Y549946D03*
X731156Y552420D03*
X717829Y549856D03*
X720303Y552330D03*
X720536Y523519D03*
X724036D03*
X759342Y543603D03*
X765935Y537009D03*
X777165Y509835D03*
X845168Y192764D03*
X851137Y199864D03*
X858622Y155614D03*
X854634Y166390D03*
X842511Y164078D03*
X842022Y152174D03*
X857700Y222300D03*
X848868Y219064D03*
X850730Y350483D03*
X841116Y348914D03*
X820059Y331701D03*
X835316Y340914D03*
X846456Y350814D03*
X808188Y404950D03*
X815541Y354089D03*
X847720Y371072D03*
X809702Y416359D03*
X822300Y418900D03*
X831650Y422612D03*
X830531Y361589D03*
X794200Y422800D03*
X811300Y395900D03*
X801200Y386700D03*
X796100D03*
X821800Y400500D03*
X821700Y403900D03*
X842820Y382172D03*
X847629Y391998D03*
X855320Y414472D03*
X830133Y353930D03*
X842916Y357214D03*
X849420Y407748D03*
X822300Y390000D03*
X804000Y441100D03*
X799000D03*
X811142Y470358D03*
X811668Y433703D03*
X820150Y433900D03*
X794900Y441100D03*
X808100D03*
X807400Y477229D03*
X803300Y491600D03*
X806888Y491398D03*
X825263Y553263D03*
X827737Y555737D03*
X812763Y548263D03*
X815237Y550737D03*
X806763Y554763D03*
X809237Y557237D03*
X797763Y554263D03*
X800237Y556737D03*
X790737Y557237D03*
X842369Y549234D03*
X839895Y546760D03*
X867653Y172764D03*
X867851Y163585D03*
X864992Y175435D03*
X864492Y206435D03*
X860868Y219764D03*
X868433Y349134D03*
X864920Y368972D03*
X861420Y367269D03*
X861484Y399069D03*
G54D25*
X265400Y446100D03*
X468000Y31500D03*
Y39500D03*
X464000Y35500D03*
X468000Y35400D03*
X472000Y35500D03*
X753800Y535000D03*
G54D23*
X201801Y684252D03*
X225601D03*
G54D32*
X421653Y130709D03*
X428740Y125985D03*
X421653Y136221D03*
X428740Y131496D03*
X421653Y144882D03*
X428740Y140158D03*
X421653Y150394D03*
X428740Y145670D03*
X421653Y159055D03*
X428740Y154331D03*
X421653Y164567D03*
X428740Y159843D03*
X421653Y173229D03*
X428740Y168504D03*
X421653Y178740D03*
X428740Y174016D03*
X435827Y130709D03*
X442913Y125985D03*
X450000Y130709D03*
X457086Y125985D03*
X464173Y130709D03*
X471260Y125985D03*
X435827Y136221D03*
X442913Y131496D03*
X450000Y136221D03*
X457086Y131496D03*
X464173Y136221D03*
X471260Y131496D03*
X435827Y144882D03*
X442913Y140158D03*
X450000Y144882D03*
X457086Y140158D03*
X464173Y144882D03*
X471260Y140158D03*
X435827Y150394D03*
X442913Y145670D03*
X450000Y150394D03*
X457086Y145670D03*
X464173Y150394D03*
X471260Y145670D03*
X435827Y159055D03*
X442913Y154331D03*
X450000Y159055D03*
X457086Y154331D03*
X464173Y159055D03*
X471260Y154331D03*
X435827Y164567D03*
X442913Y159843D03*
X450000Y164567D03*
X457086Y159843D03*
X464173Y164567D03*
X471260Y159843D03*
X435827Y173229D03*
X442913Y168504D03*
X450000Y173229D03*
X457086Y168504D03*
X464173Y173229D03*
X471260Y168504D03*
X435827Y178740D03*
X442913Y174016D03*
X450000Y178740D03*
X457086Y174016D03*
X464173Y178740D03*
X471260Y174016D03*
X506693Y130709D03*
X513779Y125985D03*
X520866Y130709D03*
X527953Y125985D03*
X535039Y130709D03*
X542126Y125985D03*
X549212Y130709D03*
X556299Y125985D03*
X506693Y136221D03*
X513779Y131496D03*
X520866Y136221D03*
X527953Y131496D03*
X535039Y136221D03*
X542126Y131496D03*
X549212Y136221D03*
X556299Y131496D03*
X506693Y144882D03*
X513779Y140158D03*
X520866Y144882D03*
X527953Y140158D03*
X535039Y144882D03*
X542126Y140158D03*
X549212Y144882D03*
X556299Y140158D03*
X506693Y150394D03*
X513779Y145670D03*
X520866Y150394D03*
X527953Y145670D03*
X535039Y150394D03*
X542126Y145670D03*
X549212Y150394D03*
X556299Y145670D03*
X506693Y159055D03*
X513779Y154331D03*
X520866Y159055D03*
X527953Y154331D03*
X535039Y159055D03*
X542126Y154331D03*
X549212Y159055D03*
X556299Y154331D03*
X506693Y164567D03*
X513779Y159843D03*
X520866Y164567D03*
X527953Y159843D03*
X535039Y164567D03*
X542126Y159843D03*
X549212Y164567D03*
X556299Y159843D03*
X506693Y173229D03*
X513779Y168504D03*
X520866Y173229D03*
X527953Y168504D03*
X535039Y173229D03*
X542126Y168504D03*
X549212Y173229D03*
X556299Y168504D03*
X506693Y178740D03*
X513779Y174016D03*
X520866Y178740D03*
X527953Y174016D03*
X535039Y178740D03*
X542126Y174016D03*
X549212Y178740D03*
X556299Y174016D03*
G54D31*
X305906Y388386D03*
G54D21*
X103940Y635460D03*
X76118Y625275D03*
X81118D03*
X76549Y680547D03*
Y675547D03*
X81549Y680547D03*
Y675547D03*
X134223Y691027D03*
X122335Y660582D03*
Y655782D03*
X83125Y719240D03*
Y724040D03*
X155400Y717700D03*
X249200Y733700D03*
Y728700D03*
Y723700D03*
Y718700D03*
Y738500D03*
X330546Y8514D03*
X325546D03*
X320546D03*
X315546D03*
X310546D03*
X305546D03*
X334782Y184928D03*
X321182Y202574D03*
X305882Y195474D03*
X305382Y190174D03*
X334882Y195478D03*
Y200478D03*
Y190478D03*
X335061Y222578D03*
X335100Y218378D03*
X323492Y214234D03*
X305862Y210014D03*
X322000Y653081D03*
X312400D03*
X317200D03*
X307600D03*
X298700Y674600D03*
X303700D03*
X305559Y720973D03*
X310559D03*
X305559Y725973D03*
X310559D03*
X299500Y725400D03*
X373073Y201889D03*
X435000Y29000D03*
X438500Y25500D03*
Y32500D03*
X491500Y71600D03*
X496500D03*
X491500Y76600D03*
X496500D03*
X516693Y46345D03*
X521493D03*
X516693Y41545D03*
X521493D03*
Y36745D03*
X516693D03*
X521493Y31945D03*
X526530Y43775D03*
X516693Y31945D03*
X567700Y28240D03*
X506500Y76600D03*
X501500D03*
Y71600D03*
X593017Y69796D03*
X588217Y74596D03*
Y69796D03*
X668847Y27107D03*
X663847D03*
X658847D03*
X653847D03*
X653601Y46761D03*
X658601D03*
X653601Y51761D03*
X658601D03*
X663601Y46761D03*
Y51761D03*
X668601Y46761D03*
Y51761D03*
X649590Y114036D03*
X710065Y455985D03*
X684399Y466984D03*
Y471984D03*
X692282Y476720D03*
X689875Y464586D03*
X698275Y438305D03*
X694272Y495786D03*
X720065Y455985D03*
Y465985D03*
X750065D03*
X760065D03*
X770065D03*
X780065D03*
X730065D03*
X740065D03*
X780065Y455985D03*
X770065D03*
X760065D03*
X750065D03*
X740065D03*
X730065D03*
X853436Y108917D03*
Y113717D03*
X853435Y90260D03*
Y95060D03*
X820065Y305985D03*
Y295985D03*
Y285985D03*
X810065Y295985D03*
Y305985D03*
X810000Y314000D03*
X810065Y325985D03*
X800065Y305985D03*
Y315985D03*
Y325985D03*
Y335985D03*
Y345985D03*
X791500Y336000D03*
X800065Y375985D03*
Y365985D03*
Y355985D03*
Y455985D03*
Y465985D03*
X790065D03*
Y455985D03*
X809000Y429400D03*
X880222Y206781D03*
X875222D03*
X896031Y228468D03*
Y223468D03*
X891031D03*
Y228468D03*
Y238468D03*
X896031D03*
X891031Y233468D03*
X896031D03*
X880122Y216781D03*
X875122D03*
X880222Y211781D03*
X875222D03*
X902091Y369397D03*
X897091D03*
X902091Y374397D03*
X897091D03*
Y379397D03*
X902091D03*
X888548Y392923D03*
X883548D03*
X893548D03*
X888548Y387923D03*
X893548D03*
X883548D03*
G54D36*
X666929Y510236D03*
X765354D03*
G54D39*
X801024Y24409D03*
X811024D03*
X821024D03*
G54D22*
X168898Y548819D03*
X184645Y539370D03*
X194094D03*
X203542Y545671D03*
X197243Y539371D03*
X194093Y564569D03*
X190944D03*
X194093Y555120D03*
X184646D03*
X153149Y536221D03*
X172048Y555120D03*
X187925Y564617D03*
X206692Y555120D03*
X165745Y564567D03*
X168895D03*
X159449Y561417D03*
X165748D03*
X172047D03*
X162598Y558268D03*
X168898D03*
X165748Y555118D03*
X159449D03*
X162599Y551970D03*
X194093D03*
X197243D03*
X181497D03*
X175197D03*
X178347D03*
X203542Y555120D03*
X187795D03*
X200393Y551970D03*
X206692Y558269D03*
Y561419D03*
Y564569D03*
X175196Y558269D03*
X190945Y545669D03*
X172047D03*
Y551970D03*
X159449Y545671D03*
X162599Y545669D03*
X165749D03*
X212991Y561419D03*
X184646Y548821D03*
Y545671D03*
X184645Y542519D03*
X206693Y542520D03*
X159449Y542521D03*
X171906Y534661D03*
X212991Y542519D03*
X156299Y545671D03*
X165749Y548819D03*
X175197Y545671D03*
X162599Y542519D03*
X168898D03*
X156299Y542521D03*
X181496Y542520D03*
X159449Y548821D03*
X194094Y542519D03*
X172047Y548819D03*
X168898Y551969D03*
X162599Y548821D03*
X162598Y561417D03*
X168898Y555119D03*
X181497Y548821D03*
X178346Y545670D03*
X181497Y545671D03*
X162595Y564567D03*
X203542Y551970D03*
X172047Y564568D03*
X200393Y548819D03*
X209842Y545669D03*
Y564567D03*
Y558268D03*
X212992Y551969D03*
Y548819D03*
X209842Y561417D03*
X212992Y564567D03*
X200393Y545669D03*
X206692Y545671D03*
X209842Y548819D03*
X212992Y545669D03*
X165777Y542555D03*
X209842Y555119D03*
Y551969D03*
X206692Y548820D03*
X206693Y551969D03*
X194094Y545669D03*
Y548820D03*
X175197Y548821D03*
X168898Y545669D03*
X153150Y539371D03*
X153149Y542521D03*
X197244Y545669D03*
Y542519D03*
X156300Y539371D03*
X197243Y589900D03*
X194094Y602362D03*
X206692Y596063D03*
X203450Y592912D03*
X194093Y596063D03*
X175196Y589764D03*
X190944Y577166D03*
X194093Y574016D03*
Y567718D03*
X190944Y574016D03*
Y567718D03*
X187795Y577166D03*
X184646D03*
X172048Y589764D03*
X187844Y574065D03*
X184645Y574166D03*
X187746Y567669D03*
X184695Y567666D03*
X184646Y570867D03*
X200393Y589764D03*
X187900Y589800D03*
X187794Y586614D03*
X203542Y589764D03*
X200393Y596063D03*
X187795Y592914D03*
X203605Y605821D03*
X187795Y602363D03*
X153149Y605513D03*
X206692Y592913D03*
X209842Y583464D03*
X212992Y586614D03*
X212991Y567718D03*
X209841Y574016D03*
X206692D03*
X168898Y567717D03*
X159449Y570866D03*
X168898Y583464D03*
Y577165D03*
X159449Y586614D03*
X162598Y580315D03*
Y586614D03*
X165748D03*
X168898D03*
X159449Y577165D03*
X156299D03*
X168898Y580315D03*
X159449D03*
X162598Y577165D03*
X165748Y580315D03*
X162598Y583464D03*
X165748Y570866D03*
Y567717D03*
X162598D03*
X172047Y570867D03*
X194094Y577166D03*
X203543Y574017D03*
X178347Y589764D03*
X181497D03*
X194093Y586614D03*
X209841Y596063D03*
X206692Y583465D03*
Y567600D03*
X212992Y580315D03*
X212991Y577165D03*
X209842Y567717D03*
X212991Y574016D03*
X190945Y599213D03*
X190944Y596063D03*
X187796Y599212D03*
X181586Y599123D03*
X212991Y583465D03*
X209841Y577165D03*
X159448Y596063D03*
X190944Y602362D03*
X203543D03*
X203542Y596063D03*
X194094Y599213D03*
X168898Y596063D03*
X212992Y602363D03*
X212991Y599212D03*
X206692Y589763D03*
X168898Y592913D03*
X162598Y596063D03*
X194093Y589764D03*
Y592913D03*
X206692Y586614D03*
X209842Y586613D03*
X212992Y589764D03*
X209841Y592913D03*
X162598Y570866D03*
X175298Y577266D03*
X172047Y567717D03*
X178346Y596064D03*
X178347Y599213D03*
X165748D03*
X168898D03*
X162598D03*
X159448D03*
X172048Y596063D03*
X190944Y592913D03*
Y589764D03*
X200393Y586614D03*
X197165Y586540D03*
X212993Y592912D03*
X209842Y589763D03*
X206692Y580315D03*
X209841D03*
X181500Y595900D03*
X200393Y592912D03*
X209841Y599212D03*
X200393D03*
X159448Y589764D03*
Y592913D03*
X162598Y589764D03*
X165748D03*
Y596063D03*
Y592913D03*
X175197D03*
X172048D03*
X181530Y592765D03*
X175197Y596063D03*
Y599213D03*
X172048D03*
X216141Y564569D03*
Y561419D03*
X219291Y542519D03*
X216141D03*
X216142Y548820D03*
X216141Y555120D03*
Y558269D03*
X222441Y548820D03*
X219291D03*
X216141Y551970D03*
X216142Y545669D03*
X216141Y580315D03*
X222440Y605512D03*
X216141Y577165D03*
Y583465D03*
Y586614D03*
Y567718D03*
X219293Y567717D03*
X216141Y574016D03*
Y599212D03*
Y589762D03*
X230600Y608100D03*
X815600Y386200D03*
G54D38*
X745669Y510236D03*
X844094D03*
G54D27*
X353543Y62913D03*
Y55039D03*
X346457Y66850D03*
Y74724D03*
Y84567D03*
X353543Y86535D03*
Y78661D03*
Y70787D03*
G54D30*
X305906Y182874D03*
G54D10*
X61024Y34449D03*
X33464D03*
X56102Y24606D03*
X38386D03*
X108268Y44292D03*
X80708D03*
X103346Y34449D03*
X85630D03*
G54D17*
X67853Y573865D03*
X99337Y683756D03*
Y678756D03*
Y673756D03*
X95200Y667500D03*
X90400D03*
X85600D03*
X197245Y555118D03*
X307567Y273592D03*
X304548Y272508D03*
Y261008D03*
X334107Y291354D03*
Y279854D03*
X307567Y349192D03*
X304267Y348092D03*
Y336592D03*
X307567Y335492D03*
Y323992D03*
X304267Y322892D03*
Y311392D03*
X307567Y310292D03*
Y298792D03*
X304267Y297692D03*
Y286192D03*
X334582Y341721D03*
Y330221D03*
X328187Y342816D03*
X328182Y329124D03*
Y317624D03*
X334593Y316584D03*
Y305084D03*
X328182Y303977D03*
Y292477D03*
X307567Y285092D03*
X304267Y373292D03*
Y361792D03*
X307567Y360692D03*
X328182Y379518D03*
Y368018D03*
X334582Y366974D03*
Y355474D03*
X328187Y354316D03*
X335000Y621200D03*
Y615400D03*
Y610200D03*
X325600Y640100D03*
X330400D03*
X335200D03*
X315520Y711720D03*
X320320D03*
X325120D03*
X588647Y28007D03*
X603943Y42806D03*
X608143Y42906D03*
X603943Y47006D03*
X608043D03*
X603747Y71407D03*
X736217Y493664D03*
X776658Y489380D03*
X771658D03*
X781658D03*
Y494380D03*
X741217Y493664D03*
X776658Y494380D03*
X771658D03*
X752602Y517850D03*
X736580Y507734D03*
X788015Y507785D03*
X783015D03*
X747602Y517850D03*
X731580Y507734D03*
X716578Y509762D03*
X721590Y511659D03*
X726590D03*
X840057Y494320D03*
X835057D03*
X825161Y507954D03*
X820161D03*
X815161D03*
X793015Y507785D03*
X900600Y201239D03*
G54D40*
X845198Y552063D03*
X837066Y543931D03*
G54D11*
X66435Y8514D03*
X61435D03*
X56435D03*
X51435D03*
X46435D03*
X41435D03*
X36435D03*
X31435D03*
X26435D03*
X21435D03*
X16435D03*
X8514Y10593D03*
Y15593D03*
Y20593D03*
Y25593D03*
Y30593D03*
Y35593D03*
Y40593D03*
Y45593D03*
Y50593D03*
Y55593D03*
Y60593D03*
X43000Y59500D03*
X51000D03*
X34000Y59400D03*
X8514Y65593D03*
Y70593D03*
Y75593D03*
Y80593D03*
Y85593D03*
Y90593D03*
Y95593D03*
Y100593D03*
Y105593D03*
Y110593D03*
Y115593D03*
Y120593D03*
Y125593D03*
Y130593D03*
Y135593D03*
Y140593D03*
Y145593D03*
Y150593D03*
Y155593D03*
Y160593D03*
Y165593D03*
Y170593D03*
Y175593D03*
Y180593D03*
Y185593D03*
Y190593D03*
Y195593D03*
Y200593D03*
Y205593D03*
Y210593D03*
Y215593D03*
Y220593D03*
Y225593D03*
Y230593D03*
Y235593D03*
Y240593D03*
Y245593D03*
Y250593D03*
Y255593D03*
Y260593D03*
Y265593D03*
Y270593D03*
Y275593D03*
Y280593D03*
Y285593D03*
Y290593D03*
Y295593D03*
Y300593D03*
Y305593D03*
Y310593D03*
Y315593D03*
Y320593D03*
Y325593D03*
Y330593D03*
Y335593D03*
Y340593D03*
Y345593D03*
Y350593D03*
Y355593D03*
Y360593D03*
Y365593D03*
Y370593D03*
Y375593D03*
Y380593D03*
Y385593D03*
Y390593D03*
Y395593D03*
Y400593D03*
Y405593D03*
Y410593D03*
Y415593D03*
Y420593D03*
Y425593D03*
Y430593D03*
Y435593D03*
Y440593D03*
Y445593D03*
Y450593D03*
Y455593D03*
Y460593D03*
Y465593D03*
Y470593D03*
Y475593D03*
Y480593D03*
Y485593D03*
Y490593D03*
X62276Y550493D03*
X8514Y495593D03*
Y500593D03*
Y505593D03*
Y510593D03*
Y515593D03*
Y520593D03*
Y525593D03*
Y530593D03*
Y535593D03*
Y540593D03*
Y545593D03*
Y550593D03*
Y555593D03*
Y560593D03*
Y565593D03*
X37660Y566400D03*
X64701Y564416D03*
X8514Y570593D03*
Y575593D03*
Y580593D03*
Y585593D03*
Y590593D03*
Y595593D03*
Y600593D03*
Y605593D03*
Y610593D03*
Y615593D03*
Y620593D03*
Y625593D03*
Y630593D03*
Y635593D03*
X42597Y571789D03*
X64701Y570716D03*
X8514Y640593D03*
Y645593D03*
Y650593D03*
Y655593D03*
Y660593D03*
Y665593D03*
Y670593D03*
Y675593D03*
Y680593D03*
Y685593D03*
Y690593D03*
Y695593D03*
Y700593D03*
Y705593D03*
Y710593D03*
X50400Y663700D03*
X50500Y667900D03*
X60600Y670900D03*
X65900Y671000D03*
X65714Y665850D03*
X60800Y660900D03*
X60700Y665900D03*
X65700Y660900D03*
X64884Y650984D03*
X37961Y659909D03*
X41100Y671800D03*
X8514Y715593D03*
Y720593D03*
X9942Y725256D03*
X12178Y729728D03*
X14414Y734200D03*
X16650Y738672D03*
X18886Y743144D03*
X21122Y747617D03*
X23358Y752089D03*
X111683Y63266D03*
Y58266D03*
Y23266D03*
Y18266D03*
Y13266D03*
X111435Y8514D03*
X106435D03*
X101435D03*
X96435D03*
X91435D03*
X86435D03*
X81435D03*
X76435D03*
X71435D03*
X111683Y118266D03*
Y113266D03*
Y108266D03*
Y103266D03*
Y98266D03*
Y93266D03*
Y88266D03*
Y83266D03*
Y78266D03*
Y73266D03*
Y68266D03*
X90768Y69755D03*
X82768D03*
X73768Y69655D03*
X111683Y203266D03*
Y198266D03*
Y193266D03*
Y188266D03*
Y183266D03*
Y178266D03*
Y173266D03*
Y168266D03*
Y163266D03*
Y158266D03*
Y153266D03*
Y148266D03*
Y278266D03*
Y273266D03*
Y268266D03*
Y263266D03*
Y258266D03*
Y253266D03*
Y248266D03*
Y243266D03*
Y238266D03*
Y233266D03*
Y228266D03*
Y223266D03*
Y218266D03*
Y213266D03*
Y208266D03*
Y348266D03*
Y343266D03*
Y338266D03*
Y333266D03*
Y328266D03*
Y323266D03*
Y318266D03*
Y313266D03*
Y308266D03*
Y303266D03*
Y298266D03*
Y293266D03*
Y288266D03*
Y283266D03*
Y418266D03*
Y413266D03*
Y408266D03*
Y403266D03*
Y398266D03*
Y393266D03*
Y388266D03*
Y383266D03*
Y378266D03*
Y373266D03*
Y368266D03*
Y363266D03*
Y358266D03*
Y353266D03*
X104000Y475500D03*
X105350Y511850D03*
X89899Y564415D03*
X119400Y511500D03*
X135012Y510200D03*
X94473Y547093D03*
X138900Y525999D03*
X136974Y534479D03*
X120500Y504600D03*
X89901Y587466D03*
X85400Y629784D03*
X86300Y703200D03*
Y708000D03*
X119000Y647000D03*
X139916Y709422D03*
X130019Y709695D03*
X139916Y705822D03*
X130019Y706095D03*
X135019D03*
X70700Y671000D03*
X70800Y660700D03*
X70600Y665800D03*
X73427Y699285D03*
X104550Y647050D03*
X104850Y639150D03*
X111300Y705500D03*
X131300Y650100D03*
X135000Y650000D03*
X76395Y755266D03*
X81395D03*
X86395D03*
X91395D03*
X96395D03*
X101395D03*
X106395D03*
X111395D03*
X116395D03*
X121395D03*
X126395D03*
X131395D03*
X136395D03*
X141395D03*
X108928Y744775D03*
X113928D03*
X118928D03*
X123928D03*
X103928D03*
X98928D03*
X93928D03*
X139916Y713022D03*
Y716622D03*
Y720222D03*
Y723822D03*
X130019Y713295D03*
Y716895D03*
Y720495D03*
X135019Y710595D03*
Y723595D03*
Y719095D03*
Y714845D03*
X130019Y724095D03*
X148000Y469000D03*
X196100Y482200D03*
X170870Y492270D03*
X198700Y513500D03*
X203350Y506700D03*
X203500Y513500D03*
X191398Y509000D03*
X156297Y558267D03*
X211700Y513500D03*
X207500Y502412D03*
X145000Y497600D03*
X191200Y522500D03*
X191300Y525900D03*
X196700Y704985D03*
X201700D03*
X206700D03*
X211700D03*
X191700D03*
X191766Y679920D03*
X151130Y703440D03*
X188500Y686800D03*
X146395Y755266D03*
X151395D03*
X156395D03*
X161395D03*
X166395D03*
X171395D03*
X176395D03*
X181395D03*
X186395D03*
X191395D03*
X196395D03*
X201395D03*
X206395D03*
X211395D03*
X213900Y474650D03*
X227100Y490300D03*
X275300Y467300D03*
X221960Y504230D03*
X278150Y637250D03*
X221700Y704985D03*
X226700D03*
X216700D03*
X267500Y645600D03*
X280500Y708100D03*
X269003Y704337D03*
X282620Y640950D03*
X262826Y662274D03*
X247725Y656375D03*
X261900Y699300D03*
X266550Y675750D03*
X247825Y670375D03*
X245971Y698400D03*
X235100Y679921D03*
X221575Y695400D03*
X279400Y686400D03*
X216395Y755266D03*
X221395D03*
X226395D03*
X231395D03*
X236395D03*
X241395D03*
X246395D03*
X251395D03*
X256395D03*
X261395D03*
X266395D03*
X271395D03*
X276395D03*
X281395D03*
X280600Y711700D03*
X282353Y740020D03*
X268820Y715100D03*
X262645Y712155D03*
X300546Y8514D03*
X296034Y9002D03*
Y14002D03*
Y19002D03*
Y24002D03*
Y29002D03*
Y34002D03*
Y39002D03*
Y44002D03*
Y49002D03*
Y54002D03*
Y59002D03*
Y64002D03*
Y69002D03*
Y74002D03*
Y79002D03*
Y84002D03*
Y89002D03*
Y94002D03*
Y99002D03*
Y104002D03*
Y109002D03*
Y114002D03*
Y119002D03*
Y124002D03*
Y129002D03*
Y134002D03*
X345069Y108533D03*
X340080Y108432D03*
X348900Y115400D03*
X305703Y202696D03*
X355600Y172900D03*
X306407Y206057D03*
X355300Y179300D03*
X354282Y187718D03*
Y191718D03*
X296034Y139002D03*
X321182Y197774D03*
X321432Y279090D03*
X321281Y266486D03*
X321197Y254433D03*
X306446Y247874D03*
X323842Y219284D03*
X305498Y213824D03*
X305382Y227474D03*
X323800Y227000D03*
X323700Y230600D03*
X321432Y342082D03*
Y329484D03*
Y316885D03*
X321882Y304374D03*
Y291874D03*
X320832Y367479D03*
X321432Y354681D03*
X320932Y377074D03*
X340606Y389899D03*
X305350Y514300D03*
X346440Y527500D03*
X350879Y520400D03*
X352734Y541826D03*
X355700Y510000D03*
X344600Y511800D03*
X326900Y507700D03*
X312289Y535181D03*
X318200Y522900D03*
X341750Y630790D03*
X342330Y620300D03*
X344940Y617720D03*
X292400Y637000D03*
X341690Y609930D03*
X341210Y602420D03*
X330800Y602610D03*
X317572Y603183D03*
X305470Y623734D03*
X311386Y633450D03*
X306300Y638600D03*
X301286Y638650D03*
X301386Y633650D03*
X306286D03*
X311186Y638550D03*
X300043Y603619D03*
X303468Y603647D03*
X297118Y668882D03*
X294804Y695204D03*
X292400Y640500D03*
X332824Y684270D03*
X348314Y643853D03*
X332800Y691970D03*
X318000Y678270D03*
X304100Y666500D03*
X300720Y704920D03*
X300520Y710020D03*
X290620Y710120D03*
X295634Y710070D03*
X290720Y705120D03*
X295620D03*
X351547Y645938D03*
X355100Y651827D03*
X301186Y643650D03*
X306486Y643750D03*
X311286D03*
X314398Y670254D03*
X340000Y662200D03*
X352800Y702960D03*
X286395Y755266D03*
X291395D03*
X296395D03*
X301395D03*
X306395D03*
X311395D03*
X316395D03*
X321395D03*
X326395D03*
X331395D03*
X336395D03*
X298570Y743670D03*
X306470Y743570D03*
X300620Y715220D03*
X290520Y715120D03*
X295820Y715220D03*
X380500Y33500D03*
Y30000D03*
X382631Y48200D03*
X382547Y52800D03*
X375300Y62150D03*
X384000Y30000D03*
X375300Y72050D03*
X357500Y104200D03*
X394070Y80840D03*
X385964Y80089D03*
X382500Y88000D03*
X363400Y115950D03*
X376000Y78400D03*
X366500Y124700D03*
X363100Y124600D03*
X428740Y179528D03*
X405100Y159300D03*
X400000Y159200D03*
X365900Y198500D03*
X362150Y214174D03*
X364000Y240100D03*
X379448Y487250D03*
X368100Y513100D03*
X387800Y529400D03*
X367500Y526800D03*
X393100Y564400D03*
X362801Y548097D03*
X366900Y499942D03*
X365164Y612620D03*
X358864D03*
X396200Y597200D03*
X394800Y609700D03*
X358646Y596456D03*
X371400Y606400D03*
X358800Y606300D03*
X365300Y606500D03*
X371400Y612700D03*
X371300Y618800D03*
X365500Y619000D03*
X358900Y618800D03*
X359000Y635600D03*
X360980Y582586D03*
X394300Y576600D03*
X372951Y576851D03*
X377714Y631280D03*
X368399Y567372D03*
X399754Y706071D03*
X388418Y650549D03*
X385700Y641300D03*
X374200Y645871D03*
X374252Y641029D03*
X386050Y701200D03*
X389168Y743572D03*
X391404Y739100D03*
X393640Y734628D03*
X395876Y730156D03*
X398112Y725684D03*
X399754Y716071D03*
Y711071D03*
X379450Y714400D03*
X496394Y30000D03*
X482727Y41870D03*
X486535Y47449D03*
X482397Y52176D03*
X457086Y179528D03*
X442913D03*
X471260D03*
X556510Y53626D03*
X518890Y59730D03*
X548550Y76480D03*
X525000Y76300D03*
X525200Y80900D03*
X513379Y103325D03*
X502379Y103194D03*
X556710Y64726D03*
X543750Y76480D03*
X513779Y179528D03*
X527953D03*
X542126D03*
X556299D03*
X608847Y34607D03*
X614032Y33307D03*
X621747Y63307D03*
X626647Y77507D03*
Y72507D03*
Y67507D03*
X576624Y193205D03*
Y198205D03*
Y203205D03*
Y208205D03*
Y213205D03*
Y223205D03*
Y228205D03*
Y233205D03*
Y238205D03*
Y243205D03*
Y248205D03*
Y253205D03*
Y258205D03*
Y263205D03*
Y268205D03*
Y273205D03*
Y278205D03*
Y333205D03*
Y338205D03*
Y343205D03*
Y348205D03*
Y353205D03*
Y358205D03*
Y363205D03*
Y368205D03*
Y373205D03*
Y378205D03*
Y383205D03*
Y388205D03*
Y393205D03*
Y398205D03*
Y403205D03*
Y408205D03*
Y413205D03*
Y418205D03*
Y423205D03*
Y428205D03*
Y433205D03*
Y438205D03*
Y443205D03*
Y448205D03*
Y498205D03*
Y503205D03*
Y508205D03*
Y513205D03*
Y518205D03*
Y523205D03*
Y528205D03*
Y533205D03*
Y538205D03*
Y543205D03*
Y548205D03*
Y553205D03*
Y558205D03*
Y563205D03*
Y568205D03*
Y573205D03*
Y578205D03*
Y583205D03*
Y588205D03*
X578710Y592712D03*
X580946Y597184D03*
X583182Y601656D03*
X585418Y606129D03*
X587654Y610601D03*
X635975Y621407D03*
X640975D03*
X715546Y8514D03*
X710546D03*
X705546D03*
X700546D03*
X695546D03*
X700065Y135985D03*
Y125985D03*
Y115985D03*
X710065D03*
Y125985D03*
Y135985D03*
X700065Y155985D03*
X710065D03*
Y145985D03*
X696159Y225829D03*
X698909Y278104D03*
X700065Y265985D03*
Y255985D03*
Y245985D03*
Y235985D03*
X710065D03*
Y245985D03*
Y255985D03*
Y265985D03*
X709625Y275991D03*
X710065Y325985D03*
Y315985D03*
X711574Y285985D03*
X708307Y295429D03*
X710065Y305985D03*
Y335985D03*
Y345985D03*
X700065Y385985D03*
Y395985D03*
Y405985D03*
Y415985D03*
X710065Y375985D03*
Y355985D03*
Y365985D03*
X706275Y445986D03*
X663500Y484000D03*
Y489000D03*
Y494000D03*
X700900Y423800D03*
X683100Y485200D03*
X679832Y494100D03*
Y489100D03*
X679100Y483300D03*
X674900D03*
X674832Y489100D03*
Y494100D03*
X682800Y480700D03*
X693392Y520482D03*
X683392D03*
X688392D03*
X705080Y521247D03*
X713189Y524511D03*
X707283D03*
X701378D03*
X695472D03*
X689567D03*
X683661D03*
X677756D03*
X662400Y519500D03*
X666800D03*
X657199Y530195D03*
X671850Y524511D03*
X645975Y621407D03*
X650975D03*
X655975D03*
X660975D03*
X665975D03*
X670975D03*
X675975D03*
X680975D03*
X685975D03*
X690975D03*
X695975D03*
X700975D03*
X705975D03*
X710975D03*
X715975D03*
X785546Y8514D03*
X780546D03*
X775546D03*
X770546D03*
X765546D03*
X760546D03*
X755546D03*
X750546D03*
X745546D03*
X740546D03*
X735546D03*
X730546D03*
X725546D03*
X720546D03*
X770065Y55985D03*
X766200Y22000D03*
X723800Y18600D03*
X770065Y65985D03*
Y75985D03*
X750065Y85985D03*
X770065D03*
X760065D03*
X740065D03*
X730065Y95985D03*
X760065D03*
X780065D03*
X770065D03*
Y105985D03*
X780065D03*
Y115985D03*
X730065Y135985D03*
Y125985D03*
Y115985D03*
Y105985D03*
X750065Y95985D03*
X740065D03*
X750065Y105985D03*
X760065D03*
X740065D03*
X750065Y115985D03*
X760065D03*
X770065D03*
X740065D03*
X750065Y125985D03*
X760065D03*
X770065D03*
X780065D03*
X740065D03*
X750065Y135985D03*
X760065D03*
X770065D03*
X780065D03*
X740065D03*
X720065Y105985D03*
Y115985D03*
Y125985D03*
Y135985D03*
Y155985D03*
X780065D03*
X730065D03*
Y145985D03*
X750065D03*
X760065D03*
X770065D03*
X780065D03*
X740065D03*
X750065Y155985D03*
X760065D03*
X770065D03*
X740065D03*
X750065Y165985D03*
X760065D03*
X770065D03*
X740065D03*
X750065Y175985D03*
X760065D03*
X770065D03*
X740065D03*
X750065Y185985D03*
X760065D03*
X770065D03*
X740065D03*
X750065Y195985D03*
X760065D03*
X770065D03*
X740065D03*
X750065Y205985D03*
X760065D03*
X770065D03*
X740065D03*
X720065Y145985D03*
X730065Y215985D03*
X773469Y277001D03*
X780065Y275985D03*
X787817Y275879D03*
X750065Y215985D03*
X760065D03*
X770065D03*
X780065D03*
X740065D03*
X780065Y265985D03*
Y255985D03*
Y245985D03*
Y235985D03*
Y225985D03*
X770065Y265985D03*
Y255985D03*
Y245985D03*
Y235985D03*
Y225985D03*
X763133Y275881D03*
X759790Y263326D03*
X760065Y255985D03*
Y245985D03*
Y235985D03*
Y225985D03*
X750065Y275985D03*
Y265985D03*
Y255985D03*
Y245985D03*
Y235985D03*
Y225985D03*
X741608Y277171D03*
X740065Y265985D03*
Y255985D03*
Y245985D03*
Y235985D03*
Y225985D03*
X730830Y276087D03*
X730065Y265985D03*
Y255985D03*
X731766Y246017D03*
X730065Y235985D03*
X730190Y223549D03*
X720237Y223228D03*
X720065Y235985D03*
X721766Y246017D03*
X720065Y255985D03*
Y265985D03*
X718617Y275736D03*
X770065Y335985D03*
X760065D03*
X720065Y325985D03*
X760065D03*
X750065D03*
X740065D03*
X730065D03*
X720065Y315985D03*
X780065Y285985D03*
X770065D03*
X760065D03*
X750065Y295985D03*
X760065D03*
X770065D03*
X780065D03*
Y305985D03*
Y315985D03*
Y325985D03*
Y335985D03*
Y345985D03*
X770065Y305985D03*
Y315985D03*
Y325985D03*
Y345985D03*
X760065Y305985D03*
Y315985D03*
Y345985D03*
X750065Y305985D03*
Y315985D03*
Y335985D03*
Y345985D03*
X740065Y305985D03*
Y315985D03*
Y335985D03*
Y345985D03*
X730065D03*
Y335985D03*
Y315985D03*
X752500Y286000D03*
X740065Y295985D03*
X741000Y286000D03*
X730065Y305985D03*
X729486Y296094D03*
X729294Y285987D03*
X721574Y285985D03*
X719049Y296011D03*
X720065Y305985D03*
Y335985D03*
Y345985D03*
X750065Y415985D03*
X760065D03*
X770065D03*
X780065D03*
X730065D03*
X740065D03*
X750065Y405985D03*
X760065D03*
X770065D03*
X780065D03*
X730065D03*
X740065D03*
X780065Y395985D03*
X770065D03*
X760065D03*
X750065D03*
X740065D03*
X730065D03*
X720065Y375985D03*
X730065Y365985D03*
Y375985D03*
Y385985D03*
X750065D03*
X760065D03*
X770065D03*
X780065D03*
X740065D03*
X750065Y375985D03*
X760065D03*
X770065D03*
X780065D03*
X740065D03*
X750065Y365985D03*
X760065D03*
X770065D03*
X780065D03*
X740065D03*
X780065Y355985D03*
X770065D03*
X760065D03*
X750065D03*
X740065D03*
X730065D03*
X720065D03*
Y365985D03*
X783800Y422800D03*
X750065Y445985D03*
X760065D03*
X770065D03*
X780065D03*
X730065D03*
X740065D03*
X750065Y435985D03*
X760065D03*
X770065D03*
X780065D03*
X740065D03*
X750065Y425985D03*
X760065D03*
X770065D03*
X780065D03*
X723800Y475164D03*
X784604Y519082D03*
X758512Y534430D03*
X747107Y536580D03*
X739334Y524156D03*
X762679Y535537D03*
X742716Y536435D03*
X738779D03*
X782086D03*
X776181D03*
X770275D03*
X725000D03*
X719394Y536305D03*
X720975Y621407D03*
X725975D03*
X730975D03*
X735975D03*
X740975D03*
X745975D03*
X750975D03*
X755975D03*
X760975D03*
X765975D03*
X770975D03*
X775975D03*
X780975D03*
X785975D03*
X850546Y8514D03*
X845546D03*
X840546D03*
X835546D03*
X830546D03*
X825546D03*
X820546D03*
X815546D03*
X810546D03*
X805546D03*
X800546D03*
X795546D03*
X790546D03*
X820065Y105985D03*
Y135985D03*
Y125985D03*
Y115985D03*
X810065Y135985D03*
Y125985D03*
Y115985D03*
X790065Y105985D03*
X800065Y115985D03*
X790065D03*
Y125985D03*
X800065D03*
Y135985D03*
X790065D03*
X820065Y155985D03*
X810065D03*
X800065D03*
X790065D03*
X820065Y145985D03*
X810065D03*
X790065D03*
X800065D03*
X820313Y276188D03*
X810065Y275985D03*
X800065D03*
X820065Y265985D03*
Y255985D03*
Y245985D03*
Y235985D03*
Y225985D03*
X810065Y265985D03*
Y255985D03*
Y245985D03*
Y235985D03*
X800065Y265985D03*
Y255985D03*
Y245985D03*
Y235985D03*
X790065Y265985D03*
Y255985D03*
Y245985D03*
Y235985D03*
Y225985D03*
X810065Y285985D03*
X800065D03*
X790065D03*
Y295985D03*
X800065D03*
X790065Y305985D03*
Y315985D03*
Y325985D03*
Y345985D03*
Y415985D03*
Y405985D03*
Y395985D03*
Y375985D03*
Y365985D03*
Y355985D03*
X816997Y371022D03*
X790065Y445985D03*
Y435985D03*
X790191Y426486D03*
X823710Y469835D03*
X805771Y518743D03*
X789604Y519082D03*
X794604D03*
X825000Y536200D03*
X817519Y536435D03*
X811614D03*
X805708D03*
X841141D03*
X837204D03*
X799803D03*
X793897D03*
X787992D03*
X790975Y621407D03*
X795975D03*
X800975D03*
X805975D03*
X810975D03*
X815975D03*
X820975D03*
X825975D03*
X830975D03*
X835975D03*
X840975D03*
X854971Y637313D03*
Y642313D03*
Y647313D03*
Y652313D03*
Y657313D03*
Y662313D03*
Y667313D03*
Y672313D03*
Y677313D03*
Y682313D03*
Y687313D03*
Y692313D03*
Y697313D03*
Y702313D03*
Y707313D03*
Y712313D03*
X916683Y62377D03*
Y57377D03*
Y52377D03*
Y47377D03*
Y42377D03*
Y37377D03*
Y32377D03*
Y27377D03*
Y22377D03*
Y17377D03*
X915546Y8514D03*
X910546D03*
X905546D03*
X900546D03*
X916683Y132377D03*
Y127377D03*
Y122377D03*
Y117377D03*
Y112377D03*
Y107377D03*
Y102377D03*
Y97377D03*
Y92377D03*
Y87377D03*
Y82377D03*
Y77377D03*
Y72377D03*
Y67377D03*
Y207377D03*
Y202377D03*
Y197377D03*
Y192377D03*
Y187377D03*
Y182377D03*
Y177377D03*
Y172377D03*
Y167377D03*
Y162377D03*
Y157377D03*
Y152377D03*
Y147377D03*
Y142377D03*
Y137377D03*
Y277377D03*
Y272377D03*
Y267377D03*
Y262377D03*
Y257377D03*
Y252377D03*
Y247377D03*
Y242377D03*
Y237377D03*
Y232377D03*
Y227377D03*
Y222377D03*
Y217377D03*
Y212377D03*
X897195Y275688D03*
X902195D03*
Y270688D03*
X897195D03*
X916683Y347377D03*
Y342377D03*
Y337377D03*
Y332377D03*
Y327377D03*
Y322377D03*
Y317377D03*
Y312377D03*
Y307377D03*
Y302377D03*
Y297377D03*
Y292377D03*
Y287377D03*
Y282377D03*
X896030Y296330D03*
X901030D03*
X900995Y290712D03*
X895995D03*
X900819Y316367D03*
X895819D03*
X900716Y311058D03*
X895716D03*
X916683Y422377D03*
Y417377D03*
Y412377D03*
Y407377D03*
Y402377D03*
Y397377D03*
Y392377D03*
Y387377D03*
Y382377D03*
Y377377D03*
Y372377D03*
Y367377D03*
Y362377D03*
Y357377D03*
Y352377D03*
Y492377D03*
Y487377D03*
Y482377D03*
Y477377D03*
Y472377D03*
Y467377D03*
Y462377D03*
Y457377D03*
Y452377D03*
Y447377D03*
Y442377D03*
Y437377D03*
Y432377D03*
Y427377D03*
Y562377D03*
Y557377D03*
Y552377D03*
Y547377D03*
Y542377D03*
Y537377D03*
Y532377D03*
Y527377D03*
Y522377D03*
Y517377D03*
Y512377D03*
Y507377D03*
Y502377D03*
Y497377D03*
Y637377D03*
Y632377D03*
Y627377D03*
Y622377D03*
Y617377D03*
Y612377D03*
Y607377D03*
Y602377D03*
Y597377D03*
Y592377D03*
Y587377D03*
Y582377D03*
Y577377D03*
Y572377D03*
Y567377D03*
Y707377D03*
Y702377D03*
Y697377D03*
Y692377D03*
Y687377D03*
Y682377D03*
Y677377D03*
Y672377D03*
Y667377D03*
Y662377D03*
Y657377D03*
Y652377D03*
Y647377D03*
Y642377D03*
X901041Y753684D03*
X903277Y749212D03*
X905513Y744740D03*
X907749Y740268D03*
X909985Y735796D03*
X912221Y731323D03*
X914457Y726851D03*
X916683Y722377D03*
Y717377D03*
Y712377D03*
G54D35*
X706299Y83661D03*
Y201771D03*
X804724Y83661D03*
Y201772D03*
G54D34*
X488838Y164744D03*
G54D13*
X34652Y111485D03*
X33297Y703990D03*
X148206Y21054D03*
X261147Y405580D03*
X486498Y356293D03*
X807831Y734367D03*
X899219Y47960D03*
G54D33*
X488838Y137225D03*
G54D19*
X89764Y238386D03*
X309252Y413583D03*
G54D24*
X163189Y669291D03*
G54D29*
X339331Y91929D03*
X360669Y49803D03*
G54D20*
X90157Y413582D03*
X309055Y157677D03*
G54D14*
X70865Y98425D03*
Y472441D03*
X314960D03*
X364173Y740157D03*
X405511Y39370D03*
X587795Y307087D03*
X590551Y472441D03*
X612204Y606299D03*
X875984Y472441D03*
Y606299D03*
Y740157D03*
G54D18*
X49212D03*
X875984Y31496D03*
G54D15*
X67853Y558117D03*
X64277Y502177D03*
X106272Y547370D03*
X89899Y558115D03*
X69904Y502077D03*
X75399Y502179D03*
X81094Y502166D03*
X86699Y502300D03*
X97926D03*
X108371Y577258D03*
X86750Y567565D03*
X93048Y577014D03*
X86750Y573864D03*
X89899D03*
X75197Y572437D03*
X165748Y558268D03*
X168898Y561417D03*
X181497Y555120D03*
X178346Y555119D03*
X187885Y552058D03*
X159412Y552006D03*
X165748Y551968D03*
X178347Y564569D03*
X203543Y561418D03*
Y564568D03*
X172020Y577050D03*
X168898Y589764D03*
Y570866D03*
X156299Y586614D03*
Y580315D03*
X159449Y567717D03*
X156299Y570866D03*
X165748Y583464D03*
X178347Y574018D03*
X203542Y580315D03*
Y586614D03*
X190944D03*
X178346Y586615D03*
X181497Y586614D03*
X178344Y577166D03*
X203542Y577165D03*
X178347Y570769D03*
X203501Y571005D03*
X148249Y695765D03*
X353700Y670900D03*
X716100Y442100D03*
X721100D03*
X857965Y273150D03*
X859407Y300314D03*
Y309914D03*
Y305114D03*
Y295314D03*
Y290314D03*
Y285314D03*
X857020Y383172D03*
Y379572D03*
Y386772D03*
X883222Y59214D03*
X888022D03*
X892822D03*
X897622D03*
X880922Y63714D03*
X885722D03*
X890522D03*
X895322D03*
X900122D03*
X897250Y81510D03*
X902050D03*
Y86310D03*
X897250D03*
Y91110D03*
X902050D03*
X897250Y95910D03*
X902050D03*
X875272Y186265D03*
X878872D03*
X860872D03*
X871672D03*
X868072D03*
X864472D03*
X878372Y191265D03*
X878872Y196265D03*
X864472D03*
X868072D03*
X871672D03*
X875272D03*
X865372Y191265D03*
X873872D03*
X869622D03*
X860872Y196265D03*
Y191265D03*
X868376Y271313D03*
X873376D03*
X864207Y300314D03*
Y309914D03*
Y305114D03*
Y295314D03*
Y290314D03*
Y285314D03*
X871420Y383172D03*
X875020D03*
Y379572D03*
X871420D03*
X867820D03*
X860620D03*
X864220D03*
X875020Y386772D03*
X871420D03*
X867820D03*
X860620D03*
X864220D03*
X867820Y383172D03*
X860620D03*
X864220D03*
G54D16*
X28782Y555119D03*
X34132Y521245D03*
X34175Y526969D03*
X29165Y532612D03*
X29058Y538228D03*
X29158Y543855D03*
X28800Y549474D03*
X33697Y560866D03*
X67852Y583313D03*
Y586463D03*
X118197Y490300D03*
X71002Y577013D03*
X186254Y463761D03*
X179000Y499800D03*
X334923Y579949D03*
X421653Y126378D03*
X428740Y121654D03*
Y135827D03*
X421653Y183071D03*
Y140551D03*
Y154725D03*
X428740Y150000D03*
X421653Y168898D03*
X428740Y164173D03*
X435827Y126378D03*
X450000D03*
X464173D03*
X442913Y121654D03*
X457086D03*
X471260D03*
X442913Y135827D03*
X457086D03*
X471260D03*
X435827Y183071D03*
X450000D03*
X464173D03*
X435827Y140551D03*
X450000D03*
X464173D03*
X435827Y154725D03*
X442913Y150000D03*
X450000Y154725D03*
X457086Y150000D03*
X464173Y154725D03*
X471260Y150000D03*
X435827Y168898D03*
X442913Y164173D03*
X450000Y168898D03*
X457086Y164173D03*
X464173Y168898D03*
X471260Y164173D03*
X506693Y126378D03*
X520866D03*
X535039D03*
X549212D03*
X513779Y121654D03*
X527953D03*
X542126D03*
X556299D03*
X513779Y135827D03*
X527953D03*
X542126D03*
X556299D03*
X506693Y183071D03*
X520866D03*
X535039D03*
X549212D03*
X506693Y140551D03*
X520866D03*
X535039D03*
X549212D03*
X506693Y154725D03*
X513779Y150000D03*
X520866Y154725D03*
X527953Y150000D03*
X535039Y154725D03*
X542126Y150000D03*
X549212Y154725D03*
X556299Y150000D03*
X506693Y168898D03*
X513779Y164173D03*
X520866Y168898D03*
X527953Y164173D03*
X535039Y168898D03*
X542126Y164173D03*
X549212Y168898D03*
X556299Y164173D03*
X576649Y39585D03*
X575300Y45967D03*
X725288Y405950D03*
X740500Y426800D03*
X716536Y523519D03*
X728036D03*
X854596Y155288D03*
X840122Y156614D03*
X843160Y169467D03*
X858632Y216929D03*
X856720Y409372D03*
X836023Y508124D03*
X805983Y508293D03*
X897803Y207684D03*
X902803D03*
X897803Y217684D03*
Y212684D03*
X902803Y217684D03*
Y212684D03*
X876451Y407949D03*
X880665Y410841D03*
X885665D03*
X890665D03*
X895665D03*
X900665D03*
G54D37*
X715000Y547027D03*
X705853Y549017D03*
X713985Y557149D03*
X696624Y548249D03*
X704756Y556381D03*
X683369Y549269D03*
X691501Y557401D03*
X681989Y540183D03*
X690121Y548315D03*
X668195Y541742D03*
X676327Y549874D03*
X655092Y536171D03*
X663224Y544303D03*
X785434Y551934D03*
X775934Y550934D03*
X784066Y559066D03*
X765434Y549934D03*
X773566Y558066D03*
X753434Y545434D03*
X761566Y553566D03*
X725853Y547117D03*
X733985Y555249D03*
X723132Y555159D03*
X822434Y550434D03*
X830566Y558566D03*
X809934Y545434D03*
X818066Y553566D03*
X803934Y551934D03*
X812066Y560066D03*
X794934Y551434D03*
X803066Y559566D03*
X793566Y560066D03*
G54D26*
X346457Y57007D03*
%LPC*%
G75*
G54D41*
G01X-36569Y-23804D02*
Y-103804D01*
G01D02*
X1258031D01*
G01X-40569Y-7804D02*
G02I-12000J0D01*
G01X-45719D02*
G02I-6850J0D01*
G01X-52569Y-23804D02*
Y8196D01*
G01X-36569Y-23804D02*
X1258031D01*
G01X-36569Y-59304D02*
X1258031D01*
G01X-36569Y-7804D02*
X-68569D01*
G01X470531Y-23804D02*
Y-103804D01*
G01X608031Y-23804D02*
Y-103804D01*
G01X723031Y-23804D02*
Y-103804D01*
G01X890531Y-23804D02*
Y-103804D01*
G01X1060531Y-23804D02*
Y-103804D01*
G01X1258031Y-23804D02*
Y-103804D01*
G01X1286031Y-7804D02*
G02I-12000J0D01*
G01X1280881D02*
G02I-6850J0D01*
G01X1274031Y-23804D02*
Y8196D01*
G01X1290031Y-7804D02*
X1258031D01*
G54D42*
G01X-9023Y-84471D02*
X-8149Y-83596D01*
X-7494Y-82138D01*
X-7057Y-80095D01*
X-7494Y-78346D01*
X-8367Y-77179D01*
X-9896Y-76304D01*
X-15791D01*
Y-93804D01*
X-8586D01*
X-7057Y-92638D01*
X-6184Y-90887D01*
X-5747Y-88846D01*
X-6184Y-86804D01*
X-7494Y-85054D01*
X-9023Y-84471D01*
X-15791D01*
G01X3674Y-93804D02*
Y-82138D01*
G01Y-84471D02*
X4766Y-83304D01*
X5858Y-82429D01*
X7386Y-82138D01*
X8477Y-82429D01*
X9788Y-83304D01*
G01X19646Y-99054D02*
X20956Y-99637D01*
X22703Y-99054D01*
X23794Y-97888D01*
X24668Y-96429D01*
X25977Y-91763D01*
X28816Y-82138D01*
G01X21829D02*
X25977Y-91763D01*
G01X45224Y-83596D02*
X43696Y-82429D01*
X42386Y-82138D01*
X40639Y-82721D01*
X39329Y-83887D01*
X38456Y-85929D01*
X38237Y-87971D01*
X38456Y-90013D01*
X39329Y-91763D01*
X40639Y-93221D01*
X42386Y-93804D01*
X43914Y-93221D01*
X45224Y-92054D01*
G01X55956Y-85929D02*
X62943D01*
X62288Y-83887D01*
X61196Y-82721D01*
X59668Y-82138D01*
X58139Y-82429D01*
X56829Y-83304D01*
X55956Y-85346D01*
X55519Y-87096D01*
Y-88846D01*
X55956Y-90596D01*
X57048Y-92346D01*
X58358Y-93512D01*
X59886Y-93804D01*
X61414Y-93221D01*
X62943Y-91471D01*
G01X99034Y-77763D02*
X97724Y-76887D01*
X96196Y-76304D01*
X94449D01*
X92484Y-77179D01*
X90956Y-78637D01*
X89864Y-80388D01*
X88991Y-83304D01*
X88772Y-85929D01*
X89209Y-88554D01*
X89864Y-90304D01*
X91174Y-92054D01*
X92703Y-93221D01*
X94231Y-93804D01*
X95759D01*
X97288Y-93221D01*
X98598Y-92346D01*
X99690Y-91180D01*
G01X115661Y-93804D02*
Y-82138D01*
G01Y-84179D02*
X114788Y-83013D01*
X113477Y-82429D01*
X111949Y-82138D01*
X110421Y-82721D01*
X109111Y-83887D01*
X108237Y-85637D01*
X107801Y-87971D01*
X108237Y-90304D01*
X109111Y-92054D01*
X110421Y-93221D01*
X111949Y-93804D01*
X113477Y-93512D01*
X114788Y-92638D01*
X115661Y-91471D01*
G01X125519Y-93804D02*
Y-82138D01*
G01Y-85054D02*
X126393Y-83596D01*
X127703Y-82429D01*
X129449Y-82138D01*
X130977Y-82429D01*
X132288Y-83596D01*
X132943Y-85637D01*
Y-93804D01*
G01X142146Y-99054D02*
X143456Y-99637D01*
X145203Y-99054D01*
X146294Y-97888D01*
X147168Y-96429D01*
X148477Y-91763D01*
X151316Y-82138D01*
G01X144329D02*
X148477Y-91763D01*
G01X164231Y-93804D02*
X162921Y-93512D01*
X161611Y-92346D01*
X160737Y-90304D01*
X160301Y-87971D01*
X160737Y-85637D01*
X161611Y-83596D01*
X162921Y-82429D01*
X164231Y-82138D01*
X165541Y-82429D01*
X166851Y-83596D01*
X167724Y-85637D01*
X167943Y-87971D01*
X167724Y-90304D01*
X166851Y-92346D01*
X165541Y-93512D01*
X164231Y-93804D01*
G01X178019D02*
Y-82138D01*
G01Y-85054D02*
X178893Y-83596D01*
X180203Y-82429D01*
X181949Y-82138D01*
X183477Y-82429D01*
X184788Y-83596D01*
X185443Y-85637D01*
Y-93804D01*
G01X214111Y-76304D02*
X219351D01*
G01X216731D02*
Y-93804D01*
G01X214111D02*
X219351D01*
G01X234231D02*
X232484Y-93512D01*
X230956Y-92346D01*
X229646Y-90596D01*
X228772Y-88554D01*
X228336Y-86221D01*
Y-83887D01*
X228772Y-81554D01*
X229646Y-79512D01*
X230956Y-77763D01*
X232484Y-76596D01*
X234231Y-76304D01*
X235977Y-76596D01*
X237506Y-77763D01*
X238816Y-79512D01*
X239690Y-81554D01*
X240126Y-83887D01*
Y-86221D01*
X239690Y-88554D01*
X238816Y-90596D01*
X237506Y-92346D01*
X235977Y-93512D01*
X234231Y-93804D01*
G01X246054D02*
Y-76304D01*
X251731Y-90887D01*
X257408Y-76304D01*
Y-93804D01*
G01X285639Y-99637D02*
X283456Y-96721D01*
X282364Y-93804D01*
Y-82138D01*
X283456Y-79221D01*
X285639Y-76304D01*
G01X298554Y-93804D02*
Y-76304D01*
X304231Y-90887D01*
X309908Y-76304D01*
Y-93804D01*
G01X321731Y-94387D02*
X321294Y-94096D01*
Y-93512D01*
X321731Y-93221D01*
X322168Y-93512D01*
Y-94096D01*
X321731Y-94387D01*
G01X335083Y-79221D02*
X336393Y-77471D01*
X337921Y-76596D01*
X339668Y-76304D01*
X341851Y-76887D01*
X343379Y-78346D01*
X343816Y-80095D01*
X343598Y-81846D01*
X342724Y-83304D01*
X338358Y-86221D01*
X336393Y-88262D01*
X335083Y-91180D01*
X334646Y-93804D01*
X343816D01*
G01X374231D02*
X372921Y-93512D01*
X371611Y-92346D01*
X370737Y-90304D01*
X370301Y-87971D01*
X370737Y-85637D01*
X371611Y-83596D01*
X372921Y-82429D01*
X374231Y-82138D01*
X375541Y-82429D01*
X376851Y-83596D01*
X377724Y-85637D01*
X377943Y-87971D01*
X377724Y-90304D01*
X376851Y-92346D01*
X375541Y-93512D01*
X374231Y-93804D01*
G01X388019D02*
Y-82138D01*
G01Y-85054D02*
X388893Y-83596D01*
X390203Y-82429D01*
X391949Y-82138D01*
X393477Y-82429D01*
X394788Y-83596D01*
X395443Y-85637D01*
Y-93804D01*
G01X409231D02*
Y-76304D01*
G01X422146Y-99054D02*
X423456Y-99637D01*
X425203Y-99054D01*
X426294Y-97888D01*
X427168Y-96429D01*
X428477Y-91763D01*
X431316Y-82138D01*
G01X424329D02*
X428477Y-91763D01*
G01X445323Y-99637D02*
X447506Y-96721D01*
X448598Y-93804D01*
Y-82138D01*
X447506Y-79221D01*
X445323Y-76304D01*
G01X176054Y-48804D02*
Y-31304D01*
X181731Y-45887D01*
X187408Y-31304D01*
Y-48804D01*
G01X199231D02*
X197921Y-48512D01*
X196611Y-47346D01*
X195737Y-45304D01*
X195301Y-42971D01*
X195737Y-40637D01*
X196611Y-38596D01*
X197921Y-37429D01*
X199231Y-37138D01*
X200541Y-37429D01*
X201851Y-38596D01*
X202724Y-40637D01*
X202943Y-42971D01*
X202724Y-45304D01*
X201851Y-47346D01*
X200541Y-48512D01*
X199231Y-48804D01*
G01X220661Y-31304D02*
Y-48804D01*
G01Y-46180D02*
X219788Y-47638D01*
X218477Y-48512D01*
X216949Y-48804D01*
X215203Y-48221D01*
X213893Y-46763D01*
X213019Y-45013D01*
X212801Y-42971D01*
X213019Y-40929D01*
X213893Y-39179D01*
X215203Y-37721D01*
X216949Y-37138D01*
X218477Y-37429D01*
X219569Y-38013D01*
X220661Y-39179D01*
G01X230956Y-40929D02*
X237943D01*
X237288Y-38887D01*
X236196Y-37721D01*
X234668Y-37138D01*
X233139Y-37429D01*
X231829Y-38304D01*
X230956Y-40346D01*
X230519Y-42096D01*
Y-43846D01*
X230956Y-45596D01*
X232048Y-47346D01*
X233358Y-48512D01*
X234886Y-48804D01*
X236414Y-48221D01*
X237943Y-46471D01*
G01X251731Y-48804D02*
Y-31304D01*
G01X504231Y-93804D02*
Y-76304D01*
X501611Y-79804D01*
G01Y-93804D02*
X506851D01*
G01X517583Y-86513D02*
X519111Y-84471D01*
X520421Y-83304D01*
X522168Y-82721D01*
X523696Y-83304D01*
X524788Y-84471D01*
X525661Y-86221D01*
X525879Y-88262D01*
X525661Y-90013D01*
X524788Y-91763D01*
X523477Y-93221D01*
X521949Y-93804D01*
X520203Y-93221D01*
X518674Y-91471D01*
X517801Y-88846D01*
X517583Y-85929D01*
X518019Y-82138D01*
X518674Y-80095D01*
X519766Y-78054D01*
X521294Y-76596D01*
X522823Y-76304D01*
X524351Y-76887D01*
X525443Y-78346D01*
G01X534428Y-90304D02*
X535737Y-92346D01*
X537484Y-93512D01*
X539449Y-93804D01*
X541196Y-93512D01*
X542943Y-92054D01*
X544034Y-90304D01*
X544253Y-88554D01*
X543816Y-86513D01*
X542288Y-85054D01*
X540759Y-84471D01*
X538794D01*
G01X540759D02*
X542069Y-83596D01*
X543161Y-82138D01*
X543598Y-80388D01*
X543161Y-78637D01*
X542069Y-77179D01*
X540104Y-76304D01*
X538139Y-76596D01*
X536174Y-77763D01*
G01X559351Y-93804D02*
Y-76304D01*
X551272Y-88846D01*
X562190D01*
G01X570083Y-79221D02*
X571393Y-77471D01*
X572921Y-76596D01*
X574668Y-76304D01*
X576851Y-76887D01*
X578379Y-78346D01*
X578816Y-80095D01*
X578598Y-81846D01*
X577724Y-83304D01*
X573358Y-86221D01*
X571393Y-88262D01*
X570083Y-91180D01*
X569646Y-93804D01*
X578816D01*
G01X491114Y-48804D02*
Y-31304D01*
X496354D01*
X498101Y-32179D01*
X499411Y-34221D01*
X499848Y-36554D01*
X499411Y-38887D01*
X498319Y-40637D01*
X496354Y-41513D01*
X491114D01*
G01X517784Y-32763D02*
X516474Y-31887D01*
X514946Y-31304D01*
X513199D01*
X511234Y-32179D01*
X509706Y-33637D01*
X508614Y-35388D01*
X507741Y-38304D01*
X507522Y-40929D01*
X507959Y-43554D01*
X508614Y-45304D01*
X509924Y-47054D01*
X511453Y-48221D01*
X512981Y-48804D01*
X514509D01*
X516038Y-48221D01*
X517348Y-47346D01*
X518440Y-46180D01*
G01X532227Y-39471D02*
X533101Y-38596D01*
X533756Y-37138D01*
X534193Y-35095D01*
X533756Y-33346D01*
X532883Y-32179D01*
X531354Y-31304D01*
X525459D01*
Y-48804D01*
X532664D01*
X534193Y-47638D01*
X535066Y-45887D01*
X535503Y-43846D01*
X535066Y-41804D01*
X533756Y-40054D01*
X532227Y-39471D01*
X525459D01*
G01X541431Y-54637D02*
X554531D01*
G01X560459Y-48804D02*
Y-31304D01*
X570503Y-48804D01*
Y-31304D01*
G01X582981Y-48804D02*
X581234Y-48512D01*
X579706Y-47346D01*
X578396Y-45596D01*
X577522Y-43554D01*
X577086Y-41221D01*
Y-38887D01*
X577522Y-36554D01*
X578396Y-34512D01*
X579706Y-32763D01*
X581234Y-31596D01*
X582981Y-31304D01*
X584727Y-31596D01*
X586256Y-32763D01*
X587566Y-34512D01*
X588440Y-36554D01*
X588876Y-38887D01*
Y-41221D01*
X588440Y-43554D01*
X587566Y-45596D01*
X586256Y-47346D01*
X584727Y-48512D01*
X582981Y-48804D01*
G01X633822Y-31304D02*
X639281Y-48804D01*
X644740Y-31304D01*
G01X661148Y-48804D02*
X652414D01*
Y-31304D01*
X661148D01*
G01X657654Y-39762D02*
X652414D01*
G01X669914Y-48804D02*
Y-31304D01*
X675373D01*
X677119Y-32179D01*
X678211Y-33346D01*
X678648Y-35679D01*
X678211Y-38013D01*
X676901Y-39471D01*
X675373Y-40346D01*
X669914D01*
G01X675373D02*
X678648Y-48804D01*
G01X691781Y-49387D02*
X691344Y-49096D01*
Y-48512D01*
X691781Y-48221D01*
X692218Y-48512D01*
Y-49096D01*
X691781Y-49387D01*
G01X661383Y-79221D02*
X662693Y-77471D01*
X664221Y-76596D01*
X665968Y-76304D01*
X668151Y-76887D01*
X669679Y-78346D01*
X670116Y-80095D01*
X669898Y-81846D01*
X669024Y-83304D01*
X664658Y-86221D01*
X662693Y-88262D01*
X661383Y-91180D01*
X660946Y-93804D01*
X670116D01*
G01X846098Y-76304D02*
Y-93804D01*
X837364D01*
G01X829034Y-91180D02*
X827725Y-92638D01*
X826196Y-93512D01*
X824231Y-93804D01*
X822266Y-93221D01*
X820738Y-92054D01*
X819646Y-90013D01*
X819428Y-87679D01*
X819864Y-85346D01*
X820956Y-83887D01*
X822485Y-82721D01*
X824013Y-82429D01*
X825541Y-82721D01*
X827506Y-83887D01*
X826851Y-76304D01*
X820956D01*
G01X812190D02*
X806731Y-93804D01*
X801272Y-76304D01*
G01X784428Y-77763D02*
X785738Y-76887D01*
X787266Y-76304D01*
X789013D01*
X790978Y-77179D01*
X792506Y-78637D01*
X793598Y-80388D01*
X794471Y-83304D01*
X794690Y-85929D01*
X794253Y-88554D01*
X793598Y-90304D01*
X792288Y-92054D01*
X790759Y-93221D01*
X789231Y-93804D01*
X787703D01*
X786174Y-93221D01*
X784864Y-92346D01*
X783772Y-91180D01*
G01X766928Y-77763D02*
X768238Y-76887D01*
X769766Y-76304D01*
X771513D01*
X773478Y-77179D01*
X775006Y-78637D01*
X776098Y-80388D01*
X776971Y-83304D01*
X777190Y-85929D01*
X776753Y-88554D01*
X776098Y-90304D01*
X774788Y-92054D01*
X773259Y-93221D01*
X771731Y-93804D01*
X770203D01*
X768674Y-93221D01*
X767364Y-92346D01*
X766272Y-91180D01*
G01X767364Y-31304D02*
Y-48804D01*
X776098D01*
G01X793161D02*
Y-37138D01*
G01Y-39179D02*
X792288Y-38013D01*
X790977Y-37429D01*
X789449Y-37138D01*
X787921Y-37721D01*
X786611Y-38887D01*
X785737Y-40637D01*
X785301Y-42971D01*
X785737Y-45304D01*
X786611Y-47054D01*
X787921Y-48221D01*
X789449Y-48804D01*
X790977Y-48512D01*
X792288Y-47638D01*
X793161Y-46471D01*
G01X802146Y-54054D02*
X803456Y-54637D01*
X805203Y-54054D01*
X806294Y-52888D01*
X807168Y-51429D01*
X808477Y-46763D01*
X811316Y-37138D01*
G01X804329D02*
X808477Y-46763D01*
G01X820956Y-40929D02*
X827943D01*
X827288Y-38887D01*
X826196Y-37721D01*
X824668Y-37138D01*
X823139Y-37429D01*
X821829Y-38304D01*
X820956Y-40346D01*
X820519Y-42096D01*
Y-43846D01*
X820956Y-45596D01*
X822048Y-47346D01*
X823358Y-48512D01*
X824886Y-48804D01*
X826414Y-48221D01*
X827943Y-46471D01*
G01X838674Y-48804D02*
Y-37138D01*
G01Y-39471D02*
X839766Y-38304D01*
X840858Y-37429D01*
X842386Y-37138D01*
X843477Y-37429D01*
X844788Y-38304D01*
G01X931781Y-93804D02*
X930034Y-93512D01*
X928506Y-92346D01*
X927196Y-90596D01*
X926322Y-88554D01*
X925886Y-86221D01*
Y-83887D01*
X926322Y-81554D01*
X927196Y-79512D01*
X928506Y-77763D01*
X930034Y-76596D01*
X931781Y-76304D01*
X933527Y-76596D01*
X935056Y-77763D01*
X936366Y-79512D01*
X937240Y-81554D01*
X937676Y-83887D01*
Y-86221D01*
X937240Y-88554D01*
X936366Y-90596D01*
X935056Y-92346D01*
X933527Y-93512D01*
X931781Y-93804D01*
G01X933527Y-89137D02*
X936148Y-93804D01*
G01X944478Y-76304D02*
Y-88846D01*
X945351Y-91471D01*
X947098Y-93221D01*
X949281Y-93804D01*
X951464Y-93221D01*
X953211Y-91471D01*
X954084Y-88846D01*
Y-76304D01*
G01X964161D02*
X969401D01*
G01X966781D02*
Y-93804D01*
G01X964161D02*
X969401D01*
G01X979259D02*
Y-76304D01*
X989303Y-93804D01*
Y-76304D01*
G01X1006584Y-77763D02*
X1005274Y-76887D01*
X1003746Y-76304D01*
X1001999D01*
X1000034Y-77179D01*
X998506Y-78637D01*
X997414Y-80388D01*
X996541Y-83304D01*
X996322Y-85929D01*
X996759Y-88554D01*
X997414Y-90304D01*
X998724Y-92054D01*
X1000253Y-93221D01*
X1001781Y-93804D01*
X1003309D01*
X1004838Y-93221D01*
X1006148Y-92346D01*
X1007240Y-91180D01*
G01X1019281Y-93804D02*
Y-85929D01*
X1014914Y-76304D01*
G01X1023648D02*
X1019281Y-85929D01*
G01X909478Y-48804D02*
Y-31304D01*
X913844D01*
X915591Y-32179D01*
X916901Y-33346D01*
X917993Y-35095D01*
X918866Y-37138D01*
X919084Y-40054D01*
X918866Y-42971D01*
X917993Y-45013D01*
X916901Y-46763D01*
X915591Y-47929D01*
X913844Y-48804D01*
X909478D01*
G01X928506Y-40929D02*
X935493D01*
X934838Y-38887D01*
X933746Y-37721D01*
X932218Y-37138D01*
X930689Y-37429D01*
X929379Y-38304D01*
X928506Y-40346D01*
X928069Y-42096D01*
Y-43846D01*
X928506Y-45596D01*
X929598Y-47346D01*
X930908Y-48512D01*
X932436Y-48804D01*
X933964Y-48221D01*
X935493Y-46471D01*
G01X946006Y-46763D02*
X947098Y-47929D01*
X948626Y-48804D01*
X949936D01*
X951246Y-48221D01*
X952119Y-47346D01*
X952556Y-46180D01*
X952338Y-44429D01*
X951464Y-43554D01*
X947534Y-41804D01*
X946661Y-39762D01*
X947098Y-38304D01*
X947971Y-37429D01*
X949281Y-37138D01*
X950591Y-37429D01*
X951901Y-38304D01*
G01X966781Y-37138D02*
Y-48804D01*
G01Y-32471D02*
X966344Y-32179D01*
Y-31596D01*
X966781Y-31304D01*
X967218Y-31596D01*
Y-32179D01*
X966781Y-32471D01*
G01X981224Y-53179D02*
X982753Y-54346D01*
X984499Y-54637D01*
X986027Y-54346D01*
X987338Y-52888D01*
X988211Y-50846D01*
Y-37138D01*
G01Y-39471D02*
X987338Y-38304D01*
X986027Y-37429D01*
X984499Y-37138D01*
X982753Y-37721D01*
X981661Y-38887D01*
X980787Y-40929D01*
X980351Y-42971D01*
X980569Y-44721D01*
X981443Y-46763D01*
X982753Y-48221D01*
X984499Y-48804D01*
X985809Y-48512D01*
X987338Y-47346D01*
X988211Y-46180D01*
G01X998069Y-48804D02*
Y-37138D01*
G01Y-40054D02*
X998943Y-38596D01*
X1000253Y-37429D01*
X1001999Y-37138D01*
X1003527Y-37429D01*
X1004838Y-38596D01*
X1005493Y-40637D01*
Y-48804D01*
G01X1016006Y-40929D02*
X1022993D01*
X1022338Y-38887D01*
X1021246Y-37721D01*
X1019718Y-37138D01*
X1018189Y-37429D01*
X1016879Y-38304D01*
X1016006Y-40346D01*
X1015569Y-42096D01*
Y-43846D01*
X1016006Y-45596D01*
X1017098Y-47346D01*
X1018408Y-48512D01*
X1019936Y-48804D01*
X1021464Y-48221D01*
X1022993Y-46471D01*
G01X1033724Y-48804D02*
Y-37138D01*
G01Y-39471D02*
X1034816Y-38304D01*
X1035908Y-37429D01*
X1037436Y-37138D01*
X1038527Y-37429D01*
X1039838Y-38304D01*
G01X1080481Y-76304D02*
X1078734Y-76887D01*
X1077424Y-78346D01*
X1076551Y-80095D01*
X1075896Y-82429D01*
X1075678Y-85054D01*
X1075896Y-87679D01*
X1076551Y-90013D01*
X1077424Y-91763D01*
X1078734Y-93221D01*
X1080481Y-93804D01*
X1082227Y-93221D01*
X1083538Y-91763D01*
X1084411Y-90013D01*
X1085066Y-87679D01*
X1085284Y-85054D01*
X1085066Y-82429D01*
X1084411Y-80095D01*
X1083538Y-78346D01*
X1082227Y-76887D01*
X1080481Y-76304D01*
G01X1097981Y-93804D02*
X1099509Y-93512D01*
X1101256Y-92638D01*
X1102348Y-91180D01*
X1102784Y-89137D01*
X1102348Y-87096D01*
X1101038Y-85346D01*
X1099073Y-84471D01*
X1096889D01*
X1095579Y-83887D01*
X1094487Y-82429D01*
X1094051Y-80388D01*
X1094706Y-78346D01*
X1096234Y-76887D01*
X1097981Y-76304D01*
X1099727Y-76887D01*
X1101256Y-78346D01*
X1101911Y-80388D01*
X1101474Y-82429D01*
X1100383Y-83887D01*
X1099073Y-84471D01*
X1096889D01*
X1094924Y-85346D01*
X1093614Y-87096D01*
X1093178Y-89137D01*
X1093614Y-91180D01*
X1094706Y-92638D01*
X1096453Y-93512D01*
X1097981Y-93804D01*
G01X1111551Y-94387D02*
X1119411Y-76304D01*
G01X1132981D02*
X1131234Y-76887D01*
X1129924Y-78346D01*
X1129051Y-80095D01*
X1128396Y-82429D01*
X1128178Y-85054D01*
X1128396Y-87679D01*
X1129051Y-90013D01*
X1129924Y-91763D01*
X1131234Y-93221D01*
X1132981Y-93804D01*
X1134727Y-93221D01*
X1136038Y-91763D01*
X1136911Y-90013D01*
X1137566Y-87679D01*
X1137784Y-85054D01*
X1137566Y-82429D01*
X1136911Y-80095D01*
X1136038Y-78346D01*
X1134727Y-76887D01*
X1132981Y-76304D01*
G01X1150044Y-93804D02*
X1150481Y-90013D01*
X1151136Y-86804D01*
X1152009Y-83887D01*
X1153101Y-80679D01*
X1154848Y-76304D01*
X1146114D01*
G01X1164051Y-94387D02*
X1171911Y-76304D01*
G01X1181333Y-79221D02*
X1182643Y-77471D01*
X1184171Y-76596D01*
X1185918Y-76304D01*
X1188101Y-76887D01*
X1189629Y-78346D01*
X1190066Y-80095D01*
X1189848Y-81846D01*
X1188974Y-83304D01*
X1184608Y-86221D01*
X1182643Y-88262D01*
X1181333Y-91180D01*
X1180896Y-93804D01*
X1190066D01*
G01X1202981Y-76304D02*
X1201234Y-76887D01*
X1199924Y-78346D01*
X1199051Y-80095D01*
X1198396Y-82429D01*
X1198178Y-85054D01*
X1198396Y-87679D01*
X1199051Y-90013D01*
X1199924Y-91763D01*
X1201234Y-93221D01*
X1202981Y-93804D01*
X1204727Y-93221D01*
X1206038Y-91763D01*
X1206911Y-90013D01*
X1207566Y-87679D01*
X1207784Y-85054D01*
X1207566Y-82429D01*
X1206911Y-80095D01*
X1206038Y-78346D01*
X1204727Y-76887D01*
X1202981Y-76304D01*
G01X1220481Y-93804D02*
Y-76304D01*
X1217861Y-79804D01*
G01Y-93804D02*
X1223101D01*
G01X1237544D02*
X1237981Y-90013D01*
X1238636Y-86804D01*
X1239509Y-83887D01*
X1240601Y-80679D01*
X1242348Y-76304D01*
X1233614D01*
G01X1128178Y-48804D02*
Y-31304D01*
X1132544D01*
X1134291Y-32179D01*
X1135601Y-33346D01*
X1136693Y-35095D01*
X1137566Y-37138D01*
X1137784Y-40054D01*
X1137566Y-42971D01*
X1136693Y-45013D01*
X1135601Y-46763D01*
X1134291Y-47929D01*
X1132544Y-48804D01*
X1128178D01*
G01X1154411D02*
Y-37138D01*
G01Y-39179D02*
X1153538Y-38013D01*
X1152227Y-37429D01*
X1150699Y-37138D01*
X1149171Y-37721D01*
X1147861Y-38887D01*
X1146987Y-40637D01*
X1146551Y-42971D01*
X1146987Y-45304D01*
X1147861Y-47054D01*
X1149171Y-48221D01*
X1150699Y-48804D01*
X1152227Y-48512D01*
X1153538Y-47638D01*
X1154411Y-46471D01*
G01X1167981Y-31304D02*
Y-48804D01*
G01X1164924Y-37138D02*
X1171038D01*
G01X1182206Y-40929D02*
X1189193D01*
X1188538Y-38887D01*
X1187446Y-37721D01*
X1185918Y-37138D01*
X1184389Y-37429D01*
X1183079Y-38304D01*
X1182206Y-40346D01*
X1181769Y-42096D01*
Y-43846D01*
X1182206Y-45596D01*
X1183298Y-47346D01*
X1184608Y-48512D01*
X1186136Y-48804D01*
X1187664Y-48221D01*
X1189193Y-46471D01*
M02*
